SYSTEM CONTROL MANAGEMENTGRAND TETON
Fri Aug 25 17:25:34 2023<NAME_2><NAME_1>NANANA1 OF 60TITLE
SHEETDATE
DEPARTMENT
SIZE
PROJECT DOCUMENT NUMBER REV
REVIEWER
DESIGNER
123
7 3 2 1 6 5 4
E
A
B
C
E
D
C
B
A
7 6 5 4
D
C



INDEX
1
DEPARTMENT REV
7 3 2 6 5 4
C
A
B
7
E
D
6 4 5 3 2 1
E
D
C
B
A
DATE
PROJECT
SHEET
DOCUMENT NUMBERDESIGNER
SIZE
REVIEWER
C
CONTENTSPAGE(S) PAGE(S) CONTENTS PAGE(S) CONTENTS



Fri Aug 25 17:25:34 2023<NAME_2><NAME_1>NANANA3 OF 60BLOCK DIAGRAM
SHEETDATE
DEPARTMENT
SIZE
PROJECT DOCUMENT NUMBER REV
REVIEWER
DESIGNER
123
7 3 2 1 6 5 4
E
A
B
C
E
D
C
B
A
7 6 5 4
D
C



Fri Aug 25 17:25:34 2023<NAME_2><NAME_1>NANANA4 OF 60SPI DIAGRAM
SHEETDATE
DEPARTMENT
SIZE
PROJECT DOCUMENT NUMBER REV
REVIEWER
DESIGNER
123
7 3 2 1 6 5 4
E
A
B
C
E
D
C
B
A
7 6 5 4
D
C



Fri Aug 25 17:25:34 2023<NAME_2><NAME_1>NANANA5 OF 60SPI MUX FOR BIOS
SHEETDATE
DEPARTMENT
SIZE
PROJECT DOCUMENT NUMBER REV
REVIEWER
DESIGNER
123
7 3 2 1 6 5 4
E
A
B
C
E
D
C
B
A
7 6 5 4
D
C



Fri Aug 25 17:25:35 2023<NAME_2><NAME_1>NANANA6 OF 60I2C DIAGRAM
SHEETDATE
DEPARTMENT
SIZE
PROJECT DOCUMENT NUMBER REV
REVIEWER
DESIGNER
123
7 3 2 1 6 5 4
E
A
B
C
E
D
C
B
A
7 6 5 4
D
C



Fri Aug 25 17:25:35 2023<NAME_2><NAME_1>NANANA7 OF 60JTAG DIAGRAM
SHEETDATE
DEPARTMENT
SIZE
PROJECT DOCUMENT NUMBER REV
REVIEWER
DESIGNER
123
7 3 2 1 6 5 4
E
A
B
C
E
D
C
B
A
7 6 5 4
D
C



Fri Aug 25 17:25:35 2023<NAME_2><NAME_1>NANANA8 OF 60POWER SEQUENCE
SHEETDATE
DEPARTMENT
SIZE
PROJECT DOCUMENT NUMBER REV
REVIEWER
DESIGNER
123
7 3 2 1 6 5 4
E
A
B
C
E
D
C
B
A
7 6 5 4
D
C



Fri Aug 25 17:25:35 2023<NAME_2><NAME_1>NANANA9 OF 60POWER SEQUENCE TIMING
SHEETDATE
DEPARTMENT
SIZE
PROJECT DOCUMENT NUMBER REV
REVIEWER
DESIGNER
123
7 3 2 1 6 5 4
E
A
B
C
E
D
C
B
A
7 6 5 4
D
C



(UNSTUFFED THE SERIES RES)Fri Aug 25 17:25:35 2023<NAME_2><NAME_1>NANANA10 OF 60OCP 3.0 SCM FINGER 1/2
P12V_AUXP12V_AUX
P2E_GPU_TX_C_DNP2E_GPU_TX_C_DPRESERVED FOR UPDATE BMCCH4104K1B00040225VUSB3_FPNL_TXN291515EMPTYEMPTYUSB3_FPNL_TXPQSPI_2_PLD_IO3QSPI_2_PLD_IO2USB_FPNL_DNUSB_FPNL_DPUSB_HOST_BMC_A_DPUSB_HOST_BMC_B_DPSGPIO_CLK_1SGPIO_DI_1SGPIO_LD_111120.1UF SHOULD CLOSED GF1 P3V_BAT_RP3V_BAT_R0.1UFEMPTY10%11RMII_TXD0RMII_TXENSMB_BMC_MM2_SDASPI_SYS_* FROM PCH1212FCONN168_ME1016810202011_SCM4413171212QSPI_2_*15TP_GF_B6300153615360TP_GF_A63CLK_100M_GPU_DN29SYS_PWRBTN_N131313102812361310223212SMB_BMC_MM5_SDASMB_BMC_MM5_SCLSMB_BMC_MM4_SDASMB_BMC_MM4_SCL13 1115131312123511121227 31113128 151344SMB_BMC_MM14_R1_SCLSMB_BMC_MM14_R1_SDA121227272712 1214 13111311133512111111343434111134131313111344464444461212361222UF16V22UFC0805CH6223MEA01X6S20%C080533.2 CHIPI3C4_SPD_SDAI3C4_SPD_SCLI3C3_SPD_SDAI3C3_SPD_SCLI3C1_SPD_SDAI3C1_SPD_SCLEMPTYSMLF16VX6S3127 261226 27121227121227121227122712271414141414 501528351134 28121227122936
101212121511RST_MB_STBY_N0CHIP351112352727271213FM_JTAG_SEL1113CHIP33.22711SMB_BMC_MM1_SCLSMB_BMC_MM14_SDAI3C2_SPD_SDAI3C2_SPD_SCL1433.2RMII_RXD1PECI_BMCHDD_LED_NPCH_BEEP_LED4949
14FM_VIRTUAL_RESEATSMB_BMC_MM14_SCLSGPIO_CLK_013131313151511USB_HOST_BMC_B_DNUSB_HOST_BMC_A_DNAC_PWR_BTN_NQSPI_2_PLD_CLKTP_GF1_B44QSPI_2_PLD_IO0QSPI_2_PLD_IO1FM_HDD_LED_NPCH_BEEP_R_LED
27 27464444SMB_BMC_MM3_SDASMB_BMC_MM3_SCLSMB_BMC_MM2_SCL121227 RESERVED SPI_TPM* FROM CPU TO TPM12SMB_BMC_MM2_SCL_R1CHIP33.2SMB_BMC_MM1_SDACHIPPWRGD_SYS_PWROKFM_DBP_BMC_PRDY_NRST_PLTRST_NRST_ROT_CPU_NFM_INTRUDER_NFM_PRSNT_1_N121212SMB_BMC_MM6_SCLSMB_BMC_MM6_SDASMB_BMC_MM7_SCLSMB_BMC_MM7_SDASMB_BMC_MM8_SCLSMB_BMC_MM9_SCLSMB_BMC_MM9_SDASMB_BMC_MM10_SCLJTAG_MB_TCKJTAG_MB_TMSTP_GF_A45CLK_100M_PCH_DPCLK_100M_PCH_DNP2E_PCH_TX_C_DPP2E_PCH_TX_C_DNP2E_PCH_RX_DN12P2E_PCH_RX_DP1227SMB_BMC_MM12_SDASMB_BMC_MM13_SCLSMB_BMC_MM13_SDAPWRGD_PSU_AC_PWROKSMB_BMC_MM8_SDA1227272712SMB_BMC_MM10_SDASMB_BMC_MM12_SCL32JTAG_MB_TDO3232JTAG_MB_TDIPWRGD_PSU_AC_PWROK_RFM_DBP_CPU_PREQ_GF_R_NFM_BMC_UARTSW_MSB_NFM_BMC_UARTSW_LSB_NIRQ_SMI_ACTIVE_GF_NCLK_100M_GPU_DP46 34133611USB3_FPNL_RXPUSB3_FPNL_RXNP2E_GPU_RX_DNP2E_GPU_RX_DPTP_GF_A62 TP_GF_B6212121212 RMII_CSRDV31UART_BIC_GF_RXD20%CH6223MEA01GOLD2441313RMII_RXD0RMII_RXERRMII_TXD1RMII_OCP_RCLKISPI_SYS_HOLD_R_IO3LPC_ESPI_SELESPI_LPC_LAD3_IO3SPI_SYS_WP_R_IO2SPI_SYS_CS0_NSPI_SYS_R_MISOSPI_SYS_R_MOSISPI_SYS_R_CLKESPI_LPC_LAD2_IO2ESPI_LPC_LAD1_IO1FM_PRSNT_1_NUART_BIC_GF_TXDUART_SYS_DBG_TXUART_SYS_DBG_RXRST_SRST_PLD_BMC_R_NSPI_TPM_CS_NFM_SOL_UART_CH_SELESPI_HOST_LPC_BMC_CLKRST_BMC_LPC_ESPI_NESPI_LPC_LAD0_IO0IRQ_SGPIO_NRST_SGPIO_RESET_NSGPIO_DO_1SGPIO_LD_0SGPIO_DI_0SGPIO_DO_0PVCCIO_PECI_BMCIRQ_BMC_LPC_SERIRQ_ESPI_GFESPI_HOST_LPC_BMC_LFRAME_NH_CPU_CATERR_LVC2_R2_NFM_PRSNT_0_R_N
CHIP0FM_PCH_BEEP_LEDCHIPCOLAY SGPIO AND REAL PIN2929291212HDD_LED_R_N
C330C329
R811
R564
R455
OA14
B50
B51
B53
B54
OB5
OB6
OB8
OB9
A48
A47
OB13
OB14
OB12
OB11
A52
A55
B39
B40
B30
B37
B34
B36
B32
B29
B31
B9
B35
B57
B56
A51
A53
B48
B47
B46
B45
B44
B43
B16
B15
B14
B13
B42
B12
B11
B28
A57
OB3
B27
B68
B65
B62
B59
B69
B66
B63
B60
A68
A65
A62
A59
A69
A66
A63
A60
A17
A18
A20
A21
OB2
OB1
OA2
OA1
B41
B20
B22
B21
B23
B25
B24
B19
B18
A35
A37
A36
A34
A56
OA12
OA11
OA10
OA9
OA8
OA7
OA6
OA5
A41
A40
A39
A38
A32
A31
A30
A29
A28
A27
A26
A25
A24
A23
A12
A11
A10
A9
A8
A7
A6
A5
A4
A3
A2
A1
A46
A44
A45
A43
OB10
OB7
OB4
OA13
OA4
OA3
B70
B67
B64
B61
B58
B55
B52
B49
B38
B33
B26
B17
B10
A70
A67
A64
A61
A58
A42
A33
A22
A19
A16
A13
B4
B8
B7
B6
B5
B2
B1
B3
A49
A50
A14
A15
A54
C174
R46
R36
R822
R243
GF1
GND_B70
PCIE_HPM_TXN_3
PCIE_HPM_TXP_3
GND_B67
PCIE_HPM_TXN_2
PCIE_HPM_TXP_2
GND_B64
PCIE_HPM_TXN_1
PCIE_HPM_TXP_1
GND_B61
PCIE_HPM_TXN_0
PCIE_HPM_TXP_0
GND_B58
RSVD1
RSVD0
GND_B55
USB1_DN
USB1_DP
GND_B52
USB2_DN
USB2_DP
GND_B49
QSPI1_D3
QSPI1_D2
QSPI1_D1
QSPI1_D0
QSPI1_CS0_N
QSPI1_CLK
QSPI0_CS1_N
P3V0_BAT
SGPIO_INTR_N
SGPIO_RESET_N
GND_B38
SGPIO1_LD
SGPIO1_DI
RSVD2
SGPIO1_DO
GND_B33
SGPIO0_LD
SGPIO0_DI
SGPIO_CLK
SGPIO0_DO
PVCCIO_PECI
PECI_BMC
GND_B26
NCSI_RXD1
NCSI_RXD0
NCSI_RXER
NCSI_TXD1
NCSI_TXD0
NCSI_TXEN
NCSI_CRS_DV
NCSI_CLK
GND_B17
QSPI0_D3
QSPI0_D2
QSPI0_D1
QSPI0_D0
QSPI0_CS0_N
QSPI0_CLK
GND_B10
RSVD3
ESPI_IO3
ESPI_IO2
ESPI_IO1
ESPI_IO0
ESPI_RESET_N
ESPI_ALERT_N
ESPI_CS0_N
ESPI_CLK
SPI0_MISO
SPI0_MOSI
SPI0_CS_N
SPI0_CLK
GND_OB10
UART0_SCM_RX
UART0_SCM_TX
GND_OB7
UART1_SCM_RX
UART1_SCM_TX
GND_OB4
PRSNT0_N
P12V_AUX_OB2
P12V_AUX_OB1
GND_A70
PCIE_HPM_RXN_3
PCIE_HPM_RXP_3
GND_A67
PCIE_HPM_RXN_2
PCIE_HPM_RXP_2
GND_A64
PCIE_HPM_RXN_1
PCIE_HPM_RXP_1
GND_A61
PCIE_HPM_RXN_0
PCIE_HPM_RXP_0
GND_A58
PRSNT1_N
IRQ_N
SPARE0
CHASI_N
RoT_CPU_RST_N
SPARE1
RST_PLTRST_BUF_N
DBP_PRDY_N
DBP_PREQ_N
SYS_PWROK
SYS_PWRBTN_N
HPM_STBY_RST_N
HPM_STBY_EN
HPM_STBY_RDY
HPM_FW_RECOVERY
GND_A42
I2C_12_SDA
I2C_12_SCL
I2C_11_SDA
I2C_11_SCL
JTAG_TDO
JTAG_TDI
JTAG_TMS
JTAG_TCK
GND_A33
I2C_10_SDA
I2C_10_SCL
I2C_9_SDA
I2C_9_SCL
I2C_8_SDA
I2C_8_SCL
I2C_7_SDA
I2C_7_SCL
I2C_6_SDA
I2C_6_SCL
GND_A22
PCIE_BMC_RX_DN
PCIE_BMC_RX_DP
GND_A19
PCIE_BMC_TX_DN
PCIE_BMC_TX_DP
GND_A16
CLK_100M_PCIE_DN
CLK_100M_PCIE_DP
GND_A13
I2C_5_SDA
I2C_5_SCL
I2C_4_SDA
I2C_4_SCL
I2C_3_SDA
I2C_3_SCL
I2C_2_SDA
I2C_2_SCL
I2C_1_SDA
I2C_1_SCL
I2C_0_SDA
I2C_0_SCL
VIRTUAL_RESEAT
GND_OA13
I3C_3_SDA
I3C_3_SCL
I3C_2_SDA
I3C_2_SCL
I3C_1_SDA
I3C_1_SCL
I3C_0_SDA
I3C_0_SCL
GND_OA4
GND_OA3
P12V_AUX_OA2
P12V_AUX_OA1
2
1
2
1
2 1R847
2 1R838
2 12 1
21
DESIGN NOTE:
DESIGN NOTE:
DESIGN NOTE:
DESIGN NOTE:
DESIGN NOTE:
2
1
21 21
21
SHEETDATE
DEPARTMENT
SIZE
PROJECT DOCUMENT NUMBER REV
REVIEWER
DESIGNER
123
7 3 2 1 6 5 4
E
A
B
C
E
D
C
B
A
7 6 5 4
D
OUT
OUT
OUT
OUT
BIOUT
OUT
IN
ININ
OUTOUT
IN
BI OUT
IN
ININ
OUTOUT
ININ
OUTOUT
OUTOUT
INBI
OUTOUT
ININ OUT OUT
OUTIN
OUT
OUTOUTOUTINOUT
BIIN
INBI
INBI
BIIN
BIIN
BIINBIIN
INBI
INBIINBIINBI
OUT
IN
IN
INBI
INBIIN
INBI
BIOUT
OUT
OUT
OUT
OUT
BIBI
IN
OUT
INOUT
OUTOUT
BI
BI
BI
BIBI
OUT
OUT
IN
ININ
BIBI
BIBI
OUTIN
IN
IN
OUTIN
OUTIN
ININ
IN
OUTOUT
ININ
OUTOUT
OUT
OUTOUTOUT
OUTOUTIN
OUTIN
IN
INBI
C



Fri Aug 25 17:25:36 2023<NAME_2><NAME_1>NANANA11 OF 60OCP 3.0 SCM FINGER 2/2
P3V3_AUXP3V3_AUXP3V3_RGM
1%0402LFCHIP1/16W100K1%FM_VIRTUAL_RESEAT1/16W2K4.7K0402LF1%2K2K1K1%1K 0402LF1/16W1%2K1/16W2KCS22002FB07PWRGD_SYS_PWROK0402LF1%EMPTYCHIP1/16W2K 0402LF1/16W5%00402LF1/16WEMPTY5%0CHIP1/16W100K1%CS41002FB09SGPIO_CLK_1
CHIP351013
271535133510133513103410121010121034131010131013352813103428221310121034
34132K364.7K4.7KCHIPSGPIO_DI_0SGPIO_LD_0CHIPCHIP101/16W1/16W1%0402LF1%0402LF1%1/16W1/16W0402LF1/16W0402LF103410SGPIO_DI_1EMPTYCHIPIRQ_SGPIO_NRST_SGPIO_RESET_N100402LFCS41002FB09PWRGD_PSU_AC_PWROKCHIP10SGPIO_CLK_0EMPTYCHIP0402LF1%1334 28171013LPC_ESPI_SELSYS_PWRBTN_NFM_THROTTLE_NFM_CPU_MSMI_CATERR_LVT3_NRMII_RXERRMII_TXENRMII_CSRDVSGPIO_LD_1SGPIO_DO_11050153412SGPIO_DO_0RST_PCA9548_SENSOR_NPWR_BTN_BMC_NRST_ROT_CPU_NCHIPCHIPCHIPCHIPEMPTYCHIPCHIPEMPTY4.7K0402LF4.7K4.7K4.7K4.7K4.7KCHIPEMPTYEMPTY4.7K4.7K10K4634281210RST_PLTRST_NEMPTY4.7K
R169
R81
R828
R823
R64
R82
R63
R76
R69
R41
R103
R161
R101
R163
R34
R66
R68
R45
R44
R40
R79
R78
R77
R73
R74
R75
21
SHEETDATE
DEPARTMENT
SIZE
PROJECT DOCUMENT NUMBER REV
REVIEWER
DESIGNER
123
7 3 2 1 6 5 4
E
A
B
C
E
D
C
B
A
7 6 5 4
D
OUT
OUT
OUT
OUT
OUT
OUT
OUT
OUT
OUT
OUT
OUT
OUT
OUT
OUT
OUT
OUT
OUT
OUT
OUT
OUT
OUT
OUT
OUT
OUT
C



PLACE CLOSE TO U5
DEPOP_20220426CHANGE TO 200OHM_20220804CHANGE EMMC IO PORT TO SD1,SD2CHANGE TO 40HM_20221206Fri Aug 25 17:25:36 2023<NAME_2><NAME_1>NANANA12 OF 60BMC 1
P0V6_DDR_VREF_AUXP3V3_AUX
P3V3_AUXPGPPA_BMC_AUXSMB_BMC_MM3_R_SCLSMB_BMC_MM3_R_SDASMB_BMC_MM4_R_SCLSMB_BMC_MM4_R_SDASMB_BMC_MM5_R_SCLSMB_BMC_MM5_R_SDASMB_BMC_MM6_SCLSMB_BMC_MM8_SCLSMB_BMC_MM8_SDASMB_BMC_MM9_R_SCLSMB_BMC_MM9_R_SDACHIPSMB_BMC_MM7_R_SDASMB_BMC_MM7_R_SCLSMB_BMC_MM6_SDASMB_BMC_MM6_R_SDASMB_BMC_MM8_R_SCLSMB_BMC_MM10_R_SDASMB_BMC_MM10_R_SCLSMB_BMC_MM6_R_SCLSMB_BMC_MM8_R_SDASMB_BMC_MM4_SDACHIP33.2SMB_BMC_MM4_SCL40.2 CHIP33.233.233.233.2SMB_BMC_MM3_SDASMB_BMC_MM3_SCLSMB_BMC_MM2_SDA33.233.233.2SMB_BMC_MM12_SDASMB_BMC_MM12_SCLRST_PFR_OVR_RTC_RFM_PFR_DSW_PWROK_N12CHIPCHIPCHIPSMB_BMC_MM2_R_SDA33.20.01UF10%CH4104K1B0033.21/16WRST_ESPI_LPC_BMC_NIRQ_ESPI_LPC_SERIRQ_ALERT0_NESPI_HOST_LPC_BMC_LFRAME_N_RESPI_HOST_LPC_BMC_CLK_RCHIPBMC_EMMC_WP_N2120UART_6_BMC_R_TXDCHIP33.2SMB_BMC_ALERT15_NFM_BMC_DBP_PRESENT_NCS12002FB064.7KEMPTYCS41002FB09CHIPSMB_BMC_MM7_SCLSMB_BMC_MM5_SDA10ESPI_LPC_LAD0_IO0ESPI_LPC_LAD1_IO1ESPI_LPC_LAD2_IO2ESPI_LPC_LAD3_IO3CHIP33.22710272712SMB_BMC_MM2_R_SCLSMB_BMC_MM1_R_SDASMB_BMC_MM1_R_SCL22CHIP10CHIPCHIPCHIPSMB_BMC_MM1_SCLFM_THERMTRIP_DLY_LVC1_R_NSMB_BMC_MM5_R_SDA33.2CHIPSMB_BMC_MM2_SCLSMB_BMC_MM1_SDA10SMB_BMC_MM12_R_SCLSMB_BMC_MM12_R_SDASMB_BMC_MM13_R_SCLSMB_BMC_MM13_R_SDASMB_BMC_MM14_R_SCLM_BMC_DDR4_MBG0M_BMC_DDR4_MBA1M_BMC_DDR4_MBA0M_BMC_DDR4_MWE_NM_BMC_DDR4_MCAS_NM_BMC_DDR4_MRAS_NM_BMC_DDR4_MCS_N20
SMB_BMC_MM13_SDASMB_BMC_MM14_SCLSMB_BMC_MM5_R_SCL33.2
AJ026000T06101034131211CHIPCS41002FB091034 20M_BMC_DDR4_DQS0_P33.2P2E_GPU_TX_C_DPP2E_GPU_TX_C_DN25VP2E_PCH_TX_C_DNP2E_PCH_TX_C_DP10%2020CHIP20CHIPCHIP102710363627SMB_BMC_MM13_SCL101227SMB_BMC_MM14_SDACHIPCHIPCHIPEMPTY4.7KSMB_BMC_MM9_SDASMB_BMC_MM9_SCL0402LFCHIP1/16W1%47K27SMB_BMC_MM7_SDA33.2
CH31006KB18C0402EMPTY12121/16W10102733.23446EMPTY04020.1UF0.1UF
SMB_BMC_MM15_R_SCL3433.2100K100KX7R
272727101027122712271010101221343646213436462627272627282728101111101110111012272121 271010271027 2626 271010272710271010272710102727101027121227102028344610202020201220122710
3412101112283446121212
1010
1027271312
202020101012101212312121
10
SMB_BMC_MM10_SCLSMB_BMC_MM10_SDA33.2SMB_BMC_MM14_R_SDA1%1%0402EMPTY100K33.2
SMLFAST2600A3-GPIC24033.2
CHIP
CHIP
33.2CHIP33.250V4.7K4.7K25VX7R10%0.1UF25V0.1UF
33.233.233.2CHIP33.233.2 CHIPCHIPCHIPEMPTYEMPTYCHIPCHIPCHIP33.233.2 CHIPCH4104K1B00SMB_BMC_MM16_R_SDA
10P2E_GPU_TX_DNX7R 25VCH4104K1B00P2E_PCH_TX_DPP2E_PCH_TX_DN10%M_BMC_DDR4_MA<13:0>CHIPCHIP3431212121211414211010%CHIPSMB_BMC_MM16_R_SCLSMB_BMC_MM15_R_SDACHIPESPI_LPC_D3_IO3ESPI_LPC_D2_IO2M_BMC_DDR4_MDM1M_BMC_DDR4_MDM0M_BMC_DDR4_MBG11012
33.2
P2E_GPU_RX_DNP2E_GPU_RX_DP100KRST_PLTRST_N10CHIP 100KCS41002FB09DP_BMC_HPD_3V3_BUF1010M_BMC_DDR4_DQ<15:0>CHIP20CS12402FB0133.2CHIPCHIPCS03322FB03M_BMC_DDR4_ALERT_NM_BMC_DDR4_DQS1_PM_BMC_DDR4_DQS0_N20CHIPCHIP33.2CHIPFM_BMC_DBP_PRESENT_R_NUART_6_BMC_R_RXDCHIPCHIP33.2SGPIO_BMC_M1_DISGPIO_BMC_M1_DOSGPIO_BMC_M1_CLKSGPIO_BMC_M1_LDCHIPCHIP33.233.233.233.24.7KCHIPEMPTY0402LFCS34702FB01RST_PLTRST_NSMB_BMC_MM10_R_SCLSMB_BMC_MM9_R_SDASMB_BMC_MM9_R_SCL1%100KCHIPFM_TPM_PRSNT_1_NFM_THERMTRIP_DLY_LVC1_R_NSMB_BMC_MM5_SCLSMB_BMC_MM7_R_SDASMB_BMC_MM7_R_SCLM_BMC_DDR4_MACT_NP2E_GPU_TX_DPP2E_PCH_RX_DNP2E_PCH_RX_DP1/16W0402LFFM_PCH_BMC_THERMTRIP_NFM_BMC_DBP_PRESENT_N0402ESPI_HOST_LPC_BMC_CLKESPI_HOST_LPC_BMC_LFRAME_NIRQ_BMC_LPC_SERIRQ_ESPI_GFBMC_EMMC_CLKBMC_EMMC_CMDBMC_EMMC_DT1BMC_EMMC_DT2BMC_EMMC_CD_NUART_6_BMC_TXDUART_6_BMC_RXDBMC_EMMC_DT4BMC_EMMC_DT5BMC_EMMC_DT6BMC_EMMC_DT7SGPIO_CLK_1SGPIO_LD_1SGPIO_DO_1SGPIO_DI_1SMB_BMC_MM15_SCLSMB_BMC_MM15_SDA10
0.1UF0.1UFX7R0402CH4104K1B00RST_BMC_LPC_ESPI_NBMC_EMMC_DT0BMC_EMMC_DT3RST_BMC_LPC_ESPI_N4.7KSMB_BMC_MM16_SDASMB_BMC_MM16_SCL33.2 CHIPIRQ_BMC_LPC_SERIRQ_ESPI_GFESPI_HOST_LPC_BMC_LFRAME_N121010RST_PLTRST_R_NSMB_BMC_MM10_R_SDACHIP200SMB_BMC_MM16_R5_SCLSMB_BMC_MM16_R5_SDA20M_BMC_DDR4_DQS1_NM_BMC_DDR4_RST_N20202020M_BMC_DDR4_MODTM_BMC_DDR4_MCKEM_BMC_DDR4_MCLK_DNM_BMC_DDR4_MCLK_DPNC_DP_BMC_TX0_NNC_DP_BMC_TX1_PNC_DP_BMC_TX1_NNC_DP_BMC_AUX_NNC_DP_BMC_AUX_PCLK_100M_GPU_DNCLK_100M_GPU_DPCLK_100M_PCH_DNCLK_100M_PCH_DPNC_DP_BMC_TX0_P1%CS02202FB0222222220IBMC_MIOZESPI_LPC_D0_IO0ESPI_LPC_D1_IO1121212101033.233.2CHIPCHIP33.2
GPIOS3||OSCCLK
GPIOS2||PEWAKE#
GPIOH7||SGPS1I1||SDA16
GPIOH6||SGPS1I0||SCL16
GPIOH5||SGPS1LD||SDA15
GPIOH4||SGPS1CK||SCL15
GPIOH3||SGPM1I
GPIOH2||SGPM1O
GPIOH1||SGPM1LD
GPIOH0||SGPM1CK
GPIOA5||MAC2LINK||SDA13||SGPM2LD||SGPS2LD
GPIOA4||MAC1LINK||SCL13||SGPM2CK||SGPS2CK
GPIOA7||MAC4LINK||SDA14||SGPM2I||SGPS2I1
GPIOA6||MAC3LINK||SCL14||SGPM2O||SGPS2I0
GPIOA3||SDA12||MDIO4
GPIOA2||SCL12||MDC4
GPIOA1||SDA11||MDIO3
GPIOA0||SCL11||MDC3
GPIOL3||SDA10
GPIOL2||SCL10
GPIOL1||SDA9
GPIOL0||SCL9
DPTXN1
DPTXP1
DPHPD
DPAUXN
DPAUXP
DPTXN0
DPTXP0
RCTXN
RCTXP
RCRXN
RCRXP
RCREFCLKN
RCREFCLKP
GPIOK7||SDA8
GPIOK1||SDA5
MCKE
GPIOW1||LAD1||ESPID1
GPIOJ5||HVI3C5SDA||SDA3
GPIOW2||LAD2||ESPID2
GPIOJ1||HVI3C3SDA||SDA1
GPIOW3||LAD3||ESPID3
MODT
GPIOK0||SCL5
MA7
GPIOJ6||HVI3C6SCL||SCL4
MWE#
MA2
MCK
GPIOW0||LAD0||ESPID0
MCAS#
GPIOJ3||HVI3C4SDA||SDA2
GPIOK2||SCL6
MA1
GPIOJ4||HVI3C5SCL||SCL3
MA9
GPIOK4||SCL7
MA4
MRAS#
MA10
GPIOK6||SCL8
GPIOJ0||HVI3C3SCL||SCL1
MA15||MBG1
GPIOK5||SDA7
MDM1
MA12
MA8
MCS#
MA5
MA6
GPIOJ7||HVI3C6SDA||SDA4
MDM0
MA11
MBA0
GPIOK3||SDA6
MA13
MA0
GPIOJ2||HVI3C4SCL||SCL2
MBA2||MBG0
MA14||MACT#
MA3
MBA1
MCK#
MVREF_U5
PERXN
PERXP
PEREFCLKN
PEREFCLKP
PERST#
PETXN
PETXP
GPIOG7||RXD9||SD2WP#||SALT16
GPIOG6||TXD9||SD2CD#||SALT15
GPIOG5||RXD8||SD2DAT3||SALT14
GPIOG4||TXD8||SD2DAT2||SALT13
GPIOG3||RXD7||SD2DAT1||SALT12
GPIOG2||TXD7||SD2DAT0||SALT11
GPIOG1||RXD6||SD2CMD||SALT10
GPIOG0||TXD6||SD2CLK||SALT9
GPIOF7||SD1WP#||PWM15
GPIOF6||SD1CD#||PWM14
GPIOF5||SD1DAT3||PWM13
GPIOF4||SD1DAT2||PWM12
GPIOF3||SD1DAT1||PWM11
GPIOF2||SD1DAT0||PWM10
GPIOF1||SD1CMD||PWM9
GPIOF0||SD1CLK||PWM8
GPIOW7||LPCRST#||ESPIRST#
GPIOW6||LSIRQ#||ESPIALT#
GPIOW5||LFRAME#||ESPICS#
GPIOW4||LCLK||ESPICK
MDQS1#
MDQS0#
MDQS1
MDQS0
MDQ15
MDQ14
MDQ13
MDQ12
MDQ11
MDQ10
MDQ9
MDQ8
MDQ7
MDQ6
MDQ5
MDQ4
MDQ3
MDQ2
MDQ1
MDQ0
MALERT#
MRESET#
MIOZ
MVREF_T5
R138
R129
R130
R131
R128
R139
R387
R762
R761
R880
R312
R400
C22
R310
AF2
AF3
AD2
AD3
AE1
AE2
AE4
AE5
AF5
AF6
A7
AD5
AD6
G5
U5
T5
L3
J5
J1
P5
V1
V2
T1
T2
U3
V4
U4
W4
W3
W1
V3
W2
P3
P2
P1
R1
R3
U1
R4
T3
R5
N3
H2
L5
K1
K2
J4
G3
H5
G4
N4
M3
H1
K3
L4
G1
F2
N1
M1
M2
M5
L1
J3
H3
F1
K5
F3
AD8
AD7
AF7
AE7
AC7
AC8
AB8
AB7
R24
T26
A13
E15
A14
D15
E12
F13
E11
D11
E13
D12
C11
A11
D19
C20
A19
C19
D20
E19
A20
B20
E18
C17
B17
D18
A17
C18
B18
A18
B21
D21
E20
A21
A22
C21
B22
E21
A23
A24
A25
C22
C23
D23
E22
D22
K25
L23
L24
K26
K24
L26
M25
M24
AB2
AC1
AA2
AB1
C7
AC3
AB3
C271
C272
R817
R818
R819
R820
R144
R137
R433
R151
R150
R148
R706
R705
R62
R580
R584
R583
R582
R590
R589
R165
R394
R71
R93
R570
R567
R168
R426
R425
R424
R423
R152
R153
R162
R236
R147
R146
C25
C24
R132
R133
R143
R142
R118
R127
R119
R120
C23C21
R115
R116
R117
14
3
4
5
6
10
11
9
7
6
11
10
9
2
12
13
8
7
0
8
5
4
2
1
0
15
13
3
12
1
U5
1/6
GPIO
I2C/SGPIO
I2C/MACLINK/SGPIO
Display Port
(End Point)PCI-Express
ESPILPC
DDR4
(RootComplex)PCI-Express
SD2/UARTI2C/MIISD1/PWMI2C/I3C21
21
21
21
2
1
21
2
1
21R311 21 21 21
2121
21 21
R879
21 21
2 12 12 12 1
21
21
21
21
21
21
21
21
21
21
21
21
2121
21
21
21 21
21
21
21
21
21 21
2
1
2
1
SHEETDATE
DEPARTMENT
SIZE
PROJECT DOCUMENT NUMBER REV
REVIEWER
DESIGNER
123
7 3 2 1 6 5 4
E
A
B
C
E
D
C
B
A
7 6 5 4
D
OUTIN
ININ
ININ
IN
BI
IN
BI
ININ
OUT
OUTOUT
BIBIBIBI
BIBIBIBIBI
OUTIN
BIOUT
OUT
ININ
OUT
IN
ININ
ININ
OUTOUT
OUTOUT
OUT
OUT
IN
BI
IN
BI
BIOUT
BI
BI
BI
OUT
OUT
BIIN
INBI
OUT
OUT
OUT
OUT
IN
BI
BI
BIOUT
BIOUT
BIOUTBIOUT
BIOUTBIOUT BI
BI
IN OUT
OUTOUTOUTOUTBI
BIOUT
BI
OUTOUT
BI
OUTOUT
OUT
OUTOUTOUTOUTOUT
OUT
OUTOUT
BIBIBI
OUTBI
BIOUT
BIOUTBI
BI
BIOUT
IN
BI
OUT
BIOUTOUT
BI
OUT
C



ADD BUFFER_20220804
CHANGE TO 22OHM_20221206HEART BEATING LEDMAC3 & MAC4 I/O VOLTAGE SELECTIONFri Aug 25 17:25:36 2023<NAME_2><NAME_1>NANANA13 OF 60BMC 2P3V3_AUXP3V3_P2V5_P1V8_RVDDP3V3_AUXP2V5_AUXP1V8_AUX
P3V3_LDO
P3V3_AUXP3V3_AUXP3V3_AUX100K CHIPFM_BIC_DEBUG_SW_NCS00002JB131/16W CHIP 0402LF5%0.1UF25VX7R10%1UFRMII_OCP_RCLKI_R_ISOFM_JTAG_TCK_MUX_BMC_SEL_R1FM_DBP_CPU_PREQ_GF_NPWRGD_SYS_PWROK_BMCCHIPSPI_BMC_BOOT_CS0_R_NPU_BMC_FWSPIABR_NPD_BIOS_MUX_EN_R_N
AST2600A3-GP47CHIPCHIPCS00002JB13SPI_BMC_CLK_RSPI_BMC_MOSI_IO0_R33.2 CHIPCHIPH_CPU1_PROCHOT_LVC1_NRST_PCA9548_SENSOR_R_NSPI_BMC_BIOS_ROM_MOSISPI_BMC_BIOS_ROM_CLK33.2SPI_BMC_TPM_CLKEMPTYEMPTYEMPTYEMPTYEMPTYFM_DEBUG_PORT_PRSNT_NCLK_GEN2_BMC_RC_OE_NFM_BMC_READY_PLD_NBMC_EMMC_RST_N33.2CHIPCHIP90.9BMC_CPLD_GPIO_2_R1
0.1UF25VC0402FM_PLT_BMC_THERMTRIP_N_RUART_BMC_1_RXDUART_BMC_1_TXDFM_DBP_BMC_PRDY_R_NPWRGD_PSU_AC_PWROK_BMCFM_VIRTUAL_RESEAT_BMCIC0.1UF10%X7RSPI_BMC_BOOT_CS0_R1_NSPI_BMC_BOOT_CS1_R1_NCHIPCHIP0TP_BMC_SPICS2_NPU_BMC_FWSPIABR_N_RPU_FWSPIWP_N_RTP_BMC_SPICS0_NIRQ_BMC_CPU_NMI_RRST_RSMRST_N27273428CS00002JB13CHIP0SMLFSPI_BMC_MISO_IO1_R3642FM_ESPI_PLD_ENSMB_BMC_ALERT4_NSMB_BMC_ALERT3_NCHIP33.2SPI_BMC_IO2_R4433.233.2CHIP33.2RST_WDTRST_PLD_R1_NFM_FLASH_LATCH_N_R1FM_BMC_READY_R_PLD_NCHIPCHIP3033.233.210254436LED_POSTCODE_2LED_POSTCODE_5UART_BMC_5_RXDUART_BMC_5_TXD33.233.2BMC_MONITERCHIP15CS09092FB15SPI_BMC_BOOT_MISO21 271011CHIP33.2BMC_EMMC_RST_R_N33.2SPI_BMC_BOOT_MOSI36CHIP33.233.22746212733.24634FM_BMC_SUSACK_N212733.2PU_SPI1ABRCHIP01112103510CHIPCHIP
ICCHIPSPI_BMC_TPM_CS2_R1_N21FM_VIRTUAL_RESEATPWRGD_PSU_AC_PWROKFM_DBP_BMC_PRDY_NFM_JTAG_TCK_MUX_BMC_SELFM_PCH_BMC_THERMTRIP_N1111CS13302FB00SMLFBEGR0278Z00FM_JTAG_SELSMB_BMC_ALERT4_R_NPWRGD_SYS_PWROKUART_BMC_1_RXD_RCHIPCHIP33.210CHIP100402LF4.7KCHIP33.233.233.233.2CHIP33.247IRQ_PCH_SCI_WHEA_NSPI_BMC_TPM_CS2_R_N4.7K4.7KCHIPCHIPPU_BMC_FWSPIABR_NGPU_FPGA_RST_NIRQ_SGPIO_N33.21010CHIP33.233.2CHIP33.2CHIP33.227CHIP3533.2 CHIP46253447283411343634121010 4836311036364211353627343513134613 291334352210112228341110 1334131327 3535132813343648361030 131336131313
21 1336
13353613
343013351011283510 21
15111011 103535 46
CHIPFM_BIOS_DEBUG_EN_R_N10%
33.233.233.2
EMPTYCHIPCHIP1/16W0402X6S10%ICLED_GREEN25VC0402X6S00 CHIPCHIP3301%4.7K4.7K CHIPFM_PECI_SEL_N4.7K CHIPRST_WDTRST_PLD_N33.233.24.7K4.7KCHIP25V1UF33.24.7K33.2BMC_HEARTBEAT_NCHIPEMPTY
13363142343533.2CHIPCHIP33.233.21033.2 CHIPCHIP0
CHIPCHIPCHIP10013 CHIP10SMLFRMII_OCP_RCLKI_R_ISOFM_PECI_SEL_R_NCHIPCHIP33.2BMC_ID_BEEP_SEL_R1CHIP35354449BMC_ID_BEEP_SEL33.2PD_CLK_125M_PHY_BMC_RGMIIFM_BMC_CRASHLOG_TRIG_R1_NFM_BIC_DEBUG_SW_N_RRMII_RXERRMII_CSRDVRMII_RXD1RMII_RXD0CHIPCHIPCHIP1113SPI_BMC_TPM_CS2_R_NSPI_BMC_BOOT_CS1_R_NAL001G6600074LVC1G66GVPWRGD_P1V0_AUX_DELAYPWRGD_P1V0_AUX_DELAY_RCH4104K1B00RMII_OCP_RCLKIRMII_OCP_RCLKI_ISO33.2SPI_BMC_BIOS_CS0_R1_NPWRGD_DSW_PWROK_R1IRQ_SMI_ACTIVE_BMC_NIRQ_SGPIO_BMC_NEMPTY33.2CLK_BUF1_GPU_FPGA_OE_R_NFM_BMC_CRASHLOG_TRIG_N
QSPI_2_PLD_IO0QSPI_2_PLD_IO333.2SPI_BMC_TPM_MOSISPI_BMC_TPM_MISOFM_ESPI_PLD_R1_ENCHIP33.2FM_SLPS3_GF_N35280402QSPI_2_PLD_CLKQSPI_2_PLD_IO1QSPI_2_PLD_IO2RST_BMC_SELF_HW_R1
CHIP
25VCHIPFM_ME_BT_DONE3513FM_PECI_SEL_NUART_BMC_1_TXD_RFM_DBP_CPU_PREQ_GF_R_NEMPTYBMC_HEARTBEAT_R_N
PU_FWSPIWP_N33.233.2CHIPSPI_BMC_BOOT_CLKIRQ_TPM_SPI_N13BATTERY_DETECTR468 CHANGE TO CS09092FB03AJ026000T064747IRQ_PCH_SCI_WHEA_R_NLED_POSTCODE_0LED_POSTCODE_1RMII_TXEN_R10101010364444444444RST_PCA9548_SENSOR_NBMC_CPLD_GPIO_2RST_BMC_SELF_HWRST_WDTRST_PLD_NFM_FLASH_LATCH_NCHIP47LED_POSTCODE_6LED_POSTCODE_7CHIP35FM_ID_LEDFM_BMC_MUX_CS_SPI_SEL_0CHIPSMB_BMC_ALERT3_R_NSPI_BMC_BIOS_ROM_MISOSPI_BMC_BIOS_ROM_IO2SPI_BMC_BIOS_ROM_IO3FM_BMC_DEBUG_SW_N46FM_BMC_READY_R_PLD_N0402X7R10%
FM_DEBUG_PORT_PRSNT_R1_NSPI_BMC_TPM_MISO_R1SPI_BMC_TPM_MOSI_R1SPI_BMC_IO3_RSPI_BMC_TPM_CLK_R1FM_SLPS3_GF_R1_NRST_RSMRST_R_NFM_BMC_ONCTL_R_NFM_THROTTLE_NH_CPU0_PROCHOT_LVC1_NCHIP33.233.2424935 27VOL_SEN_ALERT_R H_CPU1_PROCHOT_LVC1_R_NIRQ_PCH_SCI_WHEA_NFLASH_WP_STATUSCHIPFM_BMC_SUSACK_R1_NFLASH_WP_STATUS_R1RMII_TXD0_RRMII_TXD1_RFM_BIOS_DEBUG_EN_R_N33.233.233.24.7K CHIP4.7K4.7K4.7K4.7KRMII_TXD1PD_BIOS_MUX_EN_NFM_BIOS_DEBUG_EN_N1313FM_SLPS3_GF_NFM_BMC_ONCTL_R_NIRQ_BMC_PCH_NMI_NFM_BMC_SUSACK_NPU_SPI1WP_N4.7K CHIPCHIPPU_SPI1ABRPU_FWSPIWP_N3613H_CPU_CATERR_LVC2_R2_NRST_ROT_CPU_NRST_SGPIO_RESET_NFM_BMC_CPU_FBRK_OUT_R_NFM_CPU_MSMI_CATERR_LVT3_NRST_PLTRST_R_NRMII_TXENRMII_TXD013PU_SPI1WP_NSPI_BMC_BIOS_CS0_NPWRGD_DSW_PWROKIRQ_SMI_ACTIVE_GF_NIRQ_BMC_CPU_NMI
19-213/GVC-AMNB/3TIRQ_BMC_PCH_NMI_NRST_ROT_CPU_R1_NRST_SGPIO_RESET_BMC_NFM_BMC_CPU_FBRK_OUT_NFM_CPU_RMCA_CATERR_LVT3_R_N33.23022CHIP2222CHIPCHIPCHIPCHIP33.21333.2UART_BMC_5_TXD_RIRQ_SML0_ALERT_R_NUART_BMC_5_RXD_R27CS02202FB024747LED_POSTCODE_4LED_POSTCODE_3
GPIOI7||SIOSCI#
GPIOI5||SIOPBO#GPIOI6||SIOPBI#
GPIOS4||TXD10
GPIOS7||RXD11
GPIOS6||TXD11
GPIOS5||RXD10
GPIOS1||MDIO1
GPIOS0||MDC1
RGMIICK
RGMII3TXD3||GPIOC5
RGMII3TXD2||GPIOC4
RGMII3TXD1||RMII3TXD1||GPIOC3
RGMII3TXD0||RMII3TXD0||GPIOC2
RGMII3TXCTL||RMII3TXEN||GPIOC1
RGMII3TXCK||RMII3RCLKO||GPIOC0
RGMII4TXD3||NRTS3||GPIOE1
RGMII4TXD2||NDTR3||GPIOE0
RGMII4TXD1||RMII4TXD1||NRI3||GPIOD7
RGMII4TXD0||RMII4TXD0||NDSR3||GPIOD6
RGMII4TXCTL||RMII4TXEN||NDCD3||GPIOD5
RGMII4TXCK||RMII4RCLKO||NCTS3||GPIOD4
RGMII4RXD3||RMII4RXER||NRTS4||GPIOE7
RGMII4RXD2||RMII4CRSDV||NDTR4||GPIOE6
RGMII4RXD1||RMII4RXD1||NRI4||GPIOE5
RGMII4RXD0||RMII4RXD0||NDSR4||GPIOE4
RGMII4RXCTL||NDCD4||GPIOE3
RGMII4RXCK||RMII4RCLKI||NCTS4||GPIOE2
RGMII3RXD3||RMII3RXER||GPIOD3
RGMII3RXD2||RMII3CRSDV||GPIOD2
RGMII3RXD1||RMII3RXD1||GPIOD1
RGMII3RXD0||RMII3RXD0||GPIOD0
RGMII3RXCTL||GPIOC7
RGMII3RXCK||RMII3RCLKI||GPIOC6
RXD5
TXD5
GPIOY3||SALT8||WDTRST4#
GPIOY2||SALT7||WDTRST3#
GPIOY1||SALT6||WDTRST2#
GPIOY0||SALT5||WDTRST1#
GPIOB7||RXD4
GPIOB6||TXD4
GPIOB5||MDIO2
GPIOB4||MDC2
GPIOB3||SALT4
GPIOB2||SALT3
GPIOB1||SALT2
GPIOB0||SALT1
GPIOX2||SPI2CS2#
GPIOX1||SPI2CS1#
GPIOX0||SPI2CS0#
GPIOX7||SPI2DQ3||RXD12
GPIOX6||SPI2DQ2||TXD12
GPIOX5||SPI2MISO
GPIOX4||SPI2MOSI
GPIOX3||SPI2CK
GPIOZ2||SPI1WP#
GPIOZ1||SPI1ABR
GPIOZ0||SPI1CS1#
SPI1CS0#
GPIOZ7||SPI1DQ3||RXD13
GPIOZ6||SPI1DQ2||TXD13
GPIOZ5||SPI1MISO
GPIOZ4||SPI1MOSI
GPIOZ3||SPI1CK
GPIOY7||FWSPIWP#
GPIOY6||FWSPIABR GPIOY4||FWSPIDQ2
GPIOY5||FWSPIDQ3
FWSPIMISO
FWSPIMOSI
FWSPICK
GPIOV7||LPCSMI#
GPIOV6||LPCPME#
GPIOV5||LPCPD#
GPIOV4||SIOPWRGD
GPIOV3||SIOONCTRL#
GPIOV2||SIOPWREQ#
GPIOV1||SIOS5#
GPIOV0||SIOS3#
FWSPICS2#
FWSPICS1#
GPIOL4||TXD3
GPIOL5||RXD3
GPION7||RXD2
GPION6||TXD2
GPION5||NRTS2
GPION4||NDTR2
GPION3||NRI2
GPION2||NDSR2
GPION1||NDCD2
GPION0||NCTS2
GPIOM7||RXD1
GPIOM6||TXD1
GPIOM5||NRTS1
GPIOM4||NDTR1
GPIOM3||NRI1
GPIOM2||NDSR1
GPIOM1||NDCD1
GPIOM0||NCTS1
FWSPICS0#
2
1 5
3
4
R465
R466
R65
R70
R458
R763
R760
R122
R689
R242
R688
R60
R121
R401
R402
R461
C8
AD13
D8
A10
D24
D26
E25
E24
E23
F24
B24
B25
B26
C24
C26
C25
F22
G22
H23
H22
J22
H24
E26
F25
F26
F23
G24
G23
AF10
AD11
AA11
AC11
AB11
AE10
AD10
AC10
AB12
AC12
AF12
AE12
AA12
AE11
AD12
AF11
AB10
AF9
AD9
AB9
AF8
AC9
AA9
AE8
AF15
AD15
AE14
AE15
AC15
AD14
AF14
AB15
T24
P23
P24
R26
T25
R23
M26
N26
M23
P26
N24
N25
N23
P25
D13
C13
C12
B12
E14
A12
B13
D14
F15
C15
A15
B16 E16
J24
H25
G26
J23
J25
H26
K23
J26
AC14
AB13AC13
AA13
AB14 AF13
R309
R805
R816
R826
R722
R407
R643
R273
R452
R637
R494
R469
R460
R444
R442
R443
R446
R840
R96
R56
R55
R111
R680
R679
R682
R681
R678
R439
R836
R824
R821
R802
R801
R799
R774
R759
R61
R38
R427
R683
R240
R241
R239
R238
R160
R237
R37
R180
R179
R178
R177
R170
R166
CA
D8
R167
C33C32C31C30
R157
R159
R158
R155
R156
R154
U28
U5
A C
VCC
E
GND
Z
Y
2/6
MAC4 / UART 3 & 4
MAC3 / MII
ACPI
SPI2 / UART
SPI1 / UART
MII / UART/ HLPC/ GPIO
UART 1 & 2
Firmware SPI
21R173
21R172
21R171
21R468
2
1
2
1
2
1
21 21
BOM NOTE:
R395
21 21
21 21
21
21
21 21
21 21 21 21
21
21
21
21
21
21
2 1
21
21
21
21
21 21
21
21
21
21 21
21
21 21 21
21
21
21
21
21
21
2
1
2
1
2
1
2
1
21
21 21
21
21
21
SHEETDATE
DEPARTMENT
SIZE
PROJECT DOCUMENT NUMBER REV
REVIEWER
DESIGNER
R405R112
123
7 3 2 1 6 5 4
E
A
B
C
E
D
C
B
A
7 6 5 4
D IN OUT
OUT
OUTOUT IN
OUTOUTOUT
OUT
OUT
IN
IN
OUT IN
IN
OUT
IN
OUT
OUT
OUT
BIOUT
IN
OUT
OUT
OUTIN
IN
IN
OUTOUT OUT OUTOUTININ
ININ
OUT
OUTOUT
BI
OUTOUT
OUT
IN
OUT
OUTIN
BIBI
BI
OUT
OUT
BI
OUT
OUTIN
OUT
OUT
OUT
BI
OUTOUT
OUTOUT
IN
OUTIN
ININ
IN
IN
IN
INOUT
OUT
OUT
OUT
OUT
IN
BI
OUT
IN
OUT
OUT
OUTOUTOUTOUTOUT
ININ
IN
IN
OUT
IN
IN
OUT
OUTIN
OUT
IN
OUT
ININ
OUTOUTOUTOUT
OUTOUT
IN
OUTOUT
OUT
OUTIN
OUT
IN
R392
C180
C



IF IMPLEMENTING EMMC, PLEASE POP R686 AND R685AC POWER BTN1000DVTID0ID1FUNCTIONADD BOARD IDID2110110110PILOTPVTMP10EVTCHANGE CLK TO 110OHM, DTA TO 33OHM_20221221CHANGE CLK TO 110OHM, DTA TO 33OHM_20221221
Fri Aug 25 17:25:37 2023<NAME_2><NAME_1>NANANA14 OF 60BMC 3
P3V3_AUXP1V2_P1V0_I3C_VDDL1P1V8_AUXP1V8_AUX
BMC_EMMC_WP_NI3C3_SPD_SCLI3C2_SPD_SCLI3C1_SPD_SDAI3C1_SPD_SCL0402LFI3C3_SPD_SCLI3C3_SPD_SDAI3C4_SPD_SCLI3C4_SPD_SDACHIPCHIP1%FM_BOARD_BMC_REV_ID2FM_BOARD_BMC_REV_ID1FM_BOARD_BMC_REV_ID0EMPTYEMPTY1/16W 1/16W1%1/16W0402LF0402LFCHIPCHIP0402LF4.7KCHIP0402LF1/16W0402LF1K4.7K1%4.7KCS21002FB061%1K 1K1%1/16W0402LFEMPTYI3C3_SCL_RI3C3_SDA_RI3C4_SCL_RI3C4_SDA_R0402LF1/16W1%1/16WCS11102FB0311033.2CS11102FB0311033.2CHIP1K0402LF1%1/16W1/16WCS11102FB0333.233.2 CHIPCHIP110CHIPCHIPCHIP1014AC_PWR_BMC_BTN_NCS11102FB03CHIP1101010CHIP4.7K1%I3C1_SPD_SCL1012BMC_EMMC_CD_N
AJ026000T06AST2600A3-GP
CHIP1/16W1K1K
SMLFIC1%1%1K1/16W10 1414 14101014141014101410141014 101/16W1/16W141%1K1/16W1%1%0402LF1%1K 1KEMPTY1/16W1%4.7KEMPTYTMP_QCS21002FB241%EMPTY0402LF1/16W0402LF121410101414141/16W1/16WEMPTY0402LF1/16W1%4.7K1%0402LFI3C4_SPD_SCLCHIPCHIP0402LF0402LFI3C4_SPD_SDACHIP1K0402LF0402LF1%1KI3C2_SPD_SDAI3C3_SPD_SDACHIPCHIPCHIP1K0402LFAC_PWR_BMC_BTN_R_N33.2I3C1_SPD_SDAI3C2_SDA_RI3C2_SCL_RI3C2_SPD_SCL10 14I3C2_SPD_SDACS24702FB100402LF10CHIP 0402LFI3C1_SDA_RI3C1_SCL_R
I3C4SDA||FSI2DATA
I3C4SCL||FSI2CLK
I3C3SDA||FSI1DATA
I3C3SCL||FSI1CLK
I3C2SDA
I3C2SCL
I3C1SDA
I3C1SCL
GPIO18E3||EMMCDAT7||FWSPI18MISO||VBMISO
GPIO18E2||EMMCDAT6||FWSPI18MOSI||VBMOSI
GPIO18E1||EMMCDAT5||FWSPI18CK||VBCK
GPIO18E0||EMMCDAT4||FWSPI18CS#||VBCS#
GPIO18D7||EMMCWP#
GPIO18D6||EMMCCD#
GPIO18D5||EMMCDAT3
GPIO18D4||EMMCDAT2
GPIO18D3||EMMCDAT1
GPIO18D2||EMMCDAT0
GPIO18D1||EMMCCMD
GPIO18D0||EMMCCLK
RGMII2TXD3||GPIO18C1
RGMII2TXD2||GPIO18C0
RGMII2TXD1||RMII2TXD1||GPIO18B7
RGMII2TXD0||RMII2TXD0||GPIO18B6
RGMII2TXCTL||RMII2TXEN||GPIO18B5
RGMII2TXCK||RMII2RCLKO||GPIO18B4
RGMII2RXD3||RMII2RXER||GPIO18C7
RGMII2RXD2||RMII2CRSDV||GPIO18C6
RGMII2RXD1||RMII2RXD1||GPIO18C5
RGMII2RXD0||RMII2RXD0||GPIO18C4
RGMII2RXCTL||GPIO18C3
RGMII2RXCK||RMII2RCLKI||GPIO18C2
RGMII1TXD3||GPIO18A5
RGMII1TXD2||GPIO18A4
RGMII1TXD1||RMII1TXD1||GPIO18A3
RGMII1TXD0||RMII1TXD0||GPIO18A2
RGMII1TXCTL||RMII1TXEN||GPIO18A1
RGMII1TXCK||RMII1RCLKO||GPIO18A0
RGMII1RXD3||RMII1RXER||GPIO18B3
RGMII1RXD2||RMII1CRSDV||GPIO18B2
RGMII1RXD1||RMII1RXD1||GPIO18B1
RGMII1RXD0||RMII1RXD0||GPIO18B0
RGMII1RXCTL||GPIO18A7
RGMII1RXCK||RMII1RCLKI||GPIO18A6
R200
R198
R186
R184
R885
R884
R865R857R855
R858R854 R856
R197
R196
R189
R188
R191
R190
R195
R194
R687
R685
R686
R684
F5
E4
D3
C1
C2
D4
E1
E2
F4
D1
E3
D2
E6
C5
A3
D5
D6
C6
E5
C4
B1
B2
A2
B3
AF24
AE25
AE26
AF25
AE22
AF22
AE24
AF23
Y4
Y3
Y2
Y1
AB6
AC5
AB5
Y5
AA5
AC4
AA4
AB4
U5
3/6
I3C (1.2V OR 1.0V I/O)
EMMC (1.8V I/O)
MAC2 (1.8V I/O)
MAC1 (1.8V I/O)
21R201
21
21
21
21
21
21
21
2
1
21
2
1
2
1
2
1
2
1
2
1
2
1
21
21
21
21
21
21
21
21
DESIGN NOTE:
R199
R187
R185
2
1
2
1
2
1
2
1
SHEETDATE
DEPARTMENT
SIZE
PROJECT DOCUMENT NUMBER REV
REVIEWER
DESIGNER
123
7 3 2 1 6 5 4
E
A
B
C
E
D
C
B
A
7 6 5 4
D
OUT
OUT
OUTBI
OUTBI
OUTBI
IN
OUT
OUT
BI
OUT
OUT
OUT
OUT
BIBI
OUT
C



PLACE PHYSICALLY CLOSE TO AST2600 CHIPFOR CPLD UPGRATED ON MBNOTE
NOTE:
NEED ADD TEST POINT FOR ICTFOR BMCUSB2AV33SD2 I/O VOLTAGE SELECTIONPECI
RST_SPI_FLASH_N FOR SPI FLASH RESETCHANGE TO 10OHM_20221221
SD1 I/O VOLTAGE SELECTIONUSB2AV18DVT CHANGE
Fri Aug 25 17:25:37 2023<NAME_2><NAME_1>NANANA15 OF 60BMC 4P3V3_RGMP1V8_AUXP3V3_P1V8_SD1VDDP1V8_AUX
P3V3_AUX
P3V3_AUXP3V3_P1V8_SD2VDDP3V3_AUXP1V8_AUXP3V3_AUX
P3V3_RGMP3V3_RGM
P3V3_RGMP1V2_AUXP1V0_AUX
P12V_AUXP5V_AUXP3V3_AUXP2V5_AUXPGPPA_BMC_AUXP1V8_AUXP3V3_AUX
BATTERY_DETECT150.1UF25V10%0402LFBATTERY_DETECT_RADC 10SCALED TO 1.35V0402LF1/16W1K 1%CHIP040215CS22002FB072KADC 4040250V5%CH11006JB00CX8PG121009BLM18PG121SN1D/2000MA50PU_25M_BMC_CLK_EN0402LF1/16W1%4.7KNPO
0.1UFCH4104K1B00SYS_BMC_PWRBTN_R_N1%1/16W3.3V SCALED TO 1.35VCHIP1/16WPGPPA_BMC_AUX_SENSOR1%X7R10%25V0.1UF
CS11002FB07CS11002FB07EMPTY49.9ID_RST_BTN_BMC_NID_RST_BTN_BMC_R_NCHIP100CHIP0CHIPFM_PWR_BTNPWR_BTN_BMC_NSYS_BMC_PWRBTN_R_NRST_BMC_RSTBTN_OUT_N10JTAG_1_BMC_TRST_RJTAG_1_BMC_TCK_RJTAG_1_BMC_TMS_RJTAG_1_BMC_TDI_RFM_INTRUDER_N32FM_INTRUDER_R_NFM_JTAG_BMC_MUX_SELCHIP 33.2RST_BMC_RSTBTN_OUT_NSYS_BMC_PWRBTN_R1_N10035CHIP15IRQ_OC_DETECT_EN_NIRQ_UV_DETECT_NBMC_RSTIND_NPD_SP_ENTEST36340402LFCS31002FB0833.2CHIP25222836IRQ_CPU0_VRHOT_NPWRGD_PCH_PWROKFM_BIOS_POST_CMPLT_BMC_NPGPPA_BMC_AUX_SENSORP1V2_SENSORSMB_BMC_ALERT9_R_NSMB_BMC_ALERT10_R_NP1V0_SENSORSMB_BMC_ALERT12_NFM_BMC_EN_DET_RSMB_BMC_ALERT16_NJTAG_1_BMC_TDO0402LF49.9BMC_PWR_LEDRST_BMC_RSTBTN_OUT_R_NSYS_BMC_PWRBTN_R1_NFM_SPD_REMOTE_EN_RFM_ADR_COMPLETEV_VGAVS_RV_VGAHS_R15154.7K CHIPCHIP4.7K010P3V_BAT_SENSORRST_EXTRST_N1K253415221546363434P12V_SENSORP5V_SENSORP3V3_SENSORP2V5_SENSORIRQ_CPU1_VRHOT_NPWRGD_CPUPWRGD_LVC133.2IRQ_OC_DETECT_N34FM_SOL_UART_CH_SEL34343434341010CHIPFM_PCH_BEEP_LEDGPU_NVS_PWR_BRAKE_R_NP1V8_SENSORBSM_PRSNT_R_NFM_PCHHOT_R_N0JTAG_SCM_NTRSTJTAG_SCM_TCK323235 2735 27JTAG_1_BMC_TDO_R32P3V_BAT_R1/16WBMC_CLK_25M1/16WCHIP1UFCH5474KE90615CS00002JB13CHIPPWR_BTN_BMC_NBLM18PG121SN1D/2000MASMLFCX8PG12100925V4.7UFP1V8_BMC_USB2AV18SMLF35V_DACR_RV_DACG_REMPTY1UF25VCH5104KEB02CH4104K1B001UF25V10%X6SC0402X7REMPTYPECI_BMCX6SEMPTYC0402CH4104K1B0015 10EMPTY1/16WCS00002JB1315CHIPCHIPCHIP132349.9CH6221ME900C0603
ADC 52KCH4104K1B00P1V8_SENSORSCALED TO 1.35VCH4104K1B00P2V5_SENSORSCALED TO 1.35VADC 3CH4104K1B000402P3V3_SENSORADC 2SCALED TO 1.35VADC 1SMB_BMC_ALERT10_NSMB_BMC_ALERT9_NSCALED TO 1.35V15281036423533.2FM_HDD_LED_NGPU_WP_HW_CTRL_R_NCHIPFM_P12V_HSC_ENABLE_R1IRQ_PCH_TPM_SPI_NUSB_OC0_REAR_R_NFM_SOL_UART_CH_SEL_R13515P5V_SENSORCS25362FB0235H_CPU0_MEMTRIP_LVC1_N15PWR_LED42345035151%CHIP0402LFCHIPCHIP150150150CS11502FB071/16WV_DACB_R
15
34153450351134151010C04026.3V3232X7R04020.1UFP3V3_BMC_USB2AV33040210%X7R25VX6S10%4.7UF25VC060310IND10%X7R0402CH4104K1B000.1UF
23AST2600A3-GPSMLFAJ026000T06IC35340BMC_HEARTBEAT_N025V10%X6SC0603CH5474KE906IND0402LFJTAG_SCM_TDO1533.2CS03322FB031%CHIP 0402LFBMC_CLK_25M_R25MHZBF625000023SMLFMISC0.1UF25V10%0402CH4104K1B0010KCS31002FB08CHIP00040225V10%5%0402LF00CS00002JB13CHIP1/16W150402LFP3V_BAT_R1101/16WFM_BMC_SSPRST_NRST_BMC_SRST_NRST_SPI_FLASH_NBMC_CLK_25MRST_EXTRST_N1515152210K1%1/16WCHIPRST_BMC_SRST_NEMPTY1%4.7KEMPTY1%4.7K2215151515151515151535 2734212636CHIP36FM_P12V_HSC_ENABLE1%CHIP1/16W33.233.2CHIP5%JTAG_SCM_TDIJTAG_SCM_TMS1525V10%X7R04021532ADC 6CS21002FB06P1V2_SENSOR25V0402LF1/16W0.1UFCHIP1K1%15CS21002FB060402LFCHIP1/16W1%1KP1V0_SENSOR10%X7RCH4104K1B0015ADC 00402LFCS21002FB06360.1UF25VP12V_SENSORCHIP15.8K1%1/16W0402LF1%1/16W2KCS31582FB02CH4104K1B00X7R040210%272725VX7R0.1UF10%3535CHIP0402LF5.36KCS22002FB071%CHIP1/16WCHIP1/16W1%2K040225VX7R0.1UF10%0402LF1%2.87K0402LF1/16WCHIP1/16W1%CHIP2KCS22872FB03CS22002FB0725V0.1UF0402LFCHIP1/16W1.69K1%0402LF2K1%CS21692FB04ADC 7VBAT 1/3 SCALEDCH4104K1B001325VCH4104K1B00X7R0.1UF10%X7R0402CS22002FB070402LFCHIP1%CS22872FB030402LFCHIP1/16W1%1/16WX7R040210%CHIP0402LFCS22002FB071/16W1%665CHIP0402LFCS16652FB000.1UF25VX7R040210%1%CHIP0402LF
323210X6S20%10%X6S25V10%74LVC1G08GWSYS_PWRBTN_N1011ICALVC1G08009CHIPPECI_BMC_R4922UF101034USB_HOST_BMC_A_DPUSB_HOST_BMC_A_DNUSB_HOST_BMC_B_DPUSB_HOST_BMC_B_DNCHIP04215150CHIPCHIP00PECI_BMCCS22002FB07CH4104K1B0032PVCCIO_PECI_BMCUSB_HOST_BMC_B_R_DNUSB_HOST_BMC_B_R_DPUSB_HOST_BMC_A_R_DNUSB_HOST_BMC_A_R_DPP1V8_BMC_USB2AV18P3V3_BMC_USB2AV33H_CPU1_MEMTRIP_LVC1_N463534V_BMC_DDC_SCL23FM_TPM_PRSNT_0_NFM_ADR_TRIGGER_NFM_JTAG_BMC_MUX_SEL_R1FM_PMBUS_ALERT_ENV_BMC_DDC_SDAFM_PCIE_M2_SSD0_PRSNT_N23V_VGAVS0CHIPV_VGAHS15CHIP15CHIP023232315CHIP1%CS01002FB07V_DACBV_DACRV_DACGCHIP1010100402LF1/16WV_DACR_RV_DACG_RV_DACB_R
0.1UFCHIP200K1/16W 2.87KCS21002FB06IC100PFCS42002FB05SMLFNX7002AKBAM70020062P3V_BAT_SENSOR47K1%0402LF100KCS34702FB011/16WCHIPCS41002FB0904020402LF1.8V SCALED TO 0.74V
R440
R565
R225
R585
4
1
2
R462
R853
C44C40
R804
R441
R398
A6
B6
J10
K10
A4
B4
A9
C9D9
B9
D7
E10
B7
AA18
AF16
F11
U26
W26
T23
U25
V26
V24
U24
V25
AA26
Y25
AC26
Y26
AB26
Y24
AB25
AA25
Y23
AB24
AB23
W23
AA24
AA23
W24
AB22
AC23
AC24
AC22
AD25
AD24
AD23
AD22
AD26
C14
B14
C16
D16
E17
A16
D17
B10
C10 A8
B8
AF21
AE21
AD21D10
AB21
AC17
AD16
AA16
AC16
AE16
AB17
AA17
AB16
AE18
AB18
AB19
AC19
AD19
AE19
AC18
AD20
R491
R644
R479
R489
R449
R448
R316
R777
R798
R797
C314
C311
R796
R795
C309
R791
R793
R794 C307
R792 C303
R787
R790
R789
C299
R788 C295
R786
R785
C290
R776
R775
R778 C275
G
Q11
R717
R527
R528
R623 R22
R23
R25
R26
R19
R20
R24
R21
R566
C43C42
R218
R217
C45
L4
C41
L3
R211
R210
R215
OSC1
C39C38
R213
R214
C37
R212
R209
C36C35
R207
R208
53
S D
U15
U5
1 21 2
Y
B
A
VDD OUT
GNDOE
4/6
CHASSIS INTRUSION
JTAG SLAVE / MASTER - 1
PECI
MISC
JTAG MASTER - 2
ADC
FAN / THRU
USB
DAC
CHASI#
GPIOI1||MTDI2||RXD12
GPIOI0||MNTRST2||TXD12
GPIOI2||MTCK2||TXD13
GPIOI3||MTMS2||RXD13
GPIOI4||MTDO2
PECI
PECIVDD
USB2AV18
SSPRST#
GPIOP7||PWM15||HBLED#
GPIOP6||PWM14
GPIOP5||PWM13||THRUOUT2
GPIOP4||PWM12||THRUIN2
GPIOP3||PWM11||THRUOUT1
GPIOP2||PWM10||THRUIN1
GPIOP1||PWM9||THRUOUT0
GPIOP0||PWM8||THRUIN0
GPIOR7||TACH15
GPIOR6||TACH14
GPIOR5||TACH13
GPIOR4||TACH12
GPIOR3||TACH11
GPIOR2||TACH10
GPIOR1||TACH9
GPIOR0||TACH8
GPIOQ7||TACH7
GPIOQ6||TACH6
GPIOQ5||TACH5
GPIOQ4||TACH4
GPIOQ3||TACH3
GPIOQ2||TACH2
GPIOQ1||TACH1
GPIOQ0||TACH0
GPIOO7||PWM7
GPIOO6||PWM6
GPIOO5||PWM5
GPIOO4||PWM4
GPIOO3||PWM3
GPIOO2||PWM2
GPIOO1||PWM1
GPIOO0||PWM0
DDCDAT
DDCCLK
GPIOL7||VGAVS
GPIOL6||VGAHS
TMS||MTMS1
TDO||MTDO1TDI||MTDI1
TCK||MTCK1
NTRST||MNTRST1
RSTIND#
CLKIN
EXTRST#
SRST#
ENTEST
ADC15||GPIU7||SALT16
ADC14||GPIU6||SALT15
ADC13||GPIU5||SALT14
ADC12||GPIU4||SALT13
ADC11||GPIU3||SALT12
ADC10||GPIU2||SALT11
ADC9||GPIU1||SALT10
ADC8||GPIU0||SALT9
ADC7||GPIT7
ADC6||GPIT6
ADC5||GPIT5
ADC4||GPIT4
ADC3||GPIT3
ADC2||GPIT2
ADC1||GPIT1
ADC0||GPIT0
USB2B_DP
USB2B_DN
USB2A_DP
USB2A_DN
USB2AV33
DACR
DACG
DACB
GATE
VCCGND
DRAINSOURCE
21
21
21
2
1
21
21R216
21
2
1
2
1
21
21
21
2 1
DESIGN NOTE:
DESIGN NOTE:
DESIGN NOTE:
DESIGN NOTE:
DESIGN NOTE:
DESIGN NOTE:
DESIGN NOTE:
DESIGN NOTE:DESIGN NOTE:
2
1
2 1
21
21
21 21
2
1
2
1
2
1
2
1
2
1
2
1
2
1
2
1
2
1
21 21
2
1 21
21
2121
21 21
2
1
2
1
21 21
2
1
21
2
1
21
21
214 3
1 2
2
1
2
1
21
21
2
1
2
1
21
2
1
2
1
21
21
SHEETDATE
DEPARTMENT
SIZE
PROJECT DOCUMENT NUMBER REV
REVIEWER
DESIGNER
123
7 3 2 1 6 5 4
E
A
B
C
E
D
C
B
A
7 6 5 4
D
OUT
ININ
BI
OUTOUTOUTOUT
BI
OUT
IN
IN
BI
IN OUT
IN OUTIN
OUT
OUT
BI
BI
INOUT
OUTOUT
ININ
OUT
OUT
OUT
IN
OUT
OUT
OUT
IN
BIBI
OUT
IN
IN
IN
IN
ININ
OUT
IN
INININININ
OUTININ
OUT
IN
OUT
ININININ
OUT
IN
ININ
OUT
OUT
OUT
OUT
OUT
OUT
INININ
OUT
IN
OUT
IN
OUT
IN
OUT
IN
IN
OUT
BIBI
IN
OUT
IN
IN
IN
OUTOUT
OUTOUT
OUTOUTOUT
OUT
INOUT
OUTIN
IN
BIBI
BI
C26
C



Fri Aug 25 17:25:38 2023<NAME_2><NAME_1>NANANA16 OF 60BMC 5PGPPA_BMC_AUXP3V3_RTC_AUXP3V3_P1V8_I2C_I3C
P1V0_AUXP1V8_AUXP3V3_AUXP3V3_RGMP1V8_AUX
P1V2_AUX
P1V2_AUXP1V2_AUXP1V0_AUXP1V8_AUXP3V3_P1V8_SD2VDDP3V3_P2V5_P1V8_RVDDP3V3_P1V8_SD1VDDP1V2_P1V0_I3C_VDDL2P1V2_P1V0_I3C_VDDL1
P3V3_AUX17A_BMC_ADCVREFP0P3V3_STBY_DACAV332.74KCHIP 0402LFP1V8_STBY_RC_VCC18AP1V0_STBY_DP_VCC10AP1V8_STBY_DP_VCC18A0402 0402CH4104K1B000.1UF25V10%X7R04020.1UF040225V10%X7R04020.1UF25V10%X7R04020.1UF10%X7R04020.1UF25V0402X7R10%25V0.1UF0402X7R10%25V0.1UFCH5104KEB02C04020402X6S10%C0402 C0402 0402X7RP1V0_STBY_PLAVDDA_BMC_DACRESTCHIP1UF25V17171717171717171717171717CS22742FB050.1UF25V10%C0603POWER CAP DISTRIBUTE ON EACH POWER PIN22UF 22UFC0402X6S X6S20%10%10%10%10%X7R0402 0402X6S6.3V 6.3VC0603X6S20%X6S25VX6SC0402X6SC060320%6.3V22UF10%C040220%22UF6.3VC06031UF6.3VC060322UFX6S20%C04021UF25V20%X6SCH6221ME900C0603C0402C0603CH5104KEB02CH5104KEB02C040210%25V 6.3V6.3V20%1UF0.1UF25V 25V10%X6SC060325VCH5104KEB0210%X6S0.1UF25V040222UF 22UF25V10%04020402X7R X7R X6SCH6221ME900CH4104K1B0025V
CH4104K1B0025VCH4104K1B0025V25VCH4104K1B0025V25V 25V1UFX6S25V1UFCH5104KEB02X6S25V1UFX6S6.3VC060322UFX6S1UF6.3VC060322UFCH6221ME900X6S25VCH4104K1B0025V25VCH4104K1B0025V25V25V1UFX6S1UFX6SX6S25V1UF25V 25V1UFX6S25V1UFX6S6.3V22UFX6S25V1UF25V25VCH4104K1B006.3VC060322UFCH6221ME900X6SBLM18PG121SN1D/2000MACX8PG121009SMLFBLM18PG121SN1D/2000MACX8PG121009IND25V1UFCH5104KEB02X6S25V 25V1UF2200PFTMP_QCH22206KB16BLM18PG121SN1D/2000MA25V1UFCH5104KEB02X6S25VCH4104K1B0025V1UFX6S25V1UFCH5104KEB02X6S25V1UFX6S25V 25V25VCH4104K1B0025V25V 25V1UFX6SCH4104K1B00SMLFBLM18PG121SN1D/2000MACX8PG121009INDA_BMC_ADCAV33
50V
X7R
X7RX7R X7RX7RX7R X7RX7R X7RX7RX7RX7R X7RX7R X7RX7RX7RX7RX7RX7R X7RX7R X7RX7RX7RX7R10%
10%10% 10%10%10% 10%10% 10% 10%10% 10%10% 10%10%10%10%10% 10%10% 10% 10%10%10%10% 10%10% 10% 10%10% 10%10%10% 10%10%10%10% 10%10%0.1UF
0.1UF0.1UF 0.1UF0.1UF0.1UF 0.1UF0.1UF0.1UF 0.1UF0.1UF0.1UF0.1UF0.1UF0.1UF0.1UF0.1UF0.1UF 0.1UF0.1UF0.1UF0.1UF0402
04020402 040204020402 0402040204020402 04020402040204020402 04020402 04020402040220% 20%20%20%C0402 C0402 C0402C0402C0402C0402 C0402C0402C0402C0402 C040249.9KCHIP49.9KCS34992FB051%1/16WCS34992FB05A_BMC_ADCREXT0A_BMC_ADCVREFN0P3V3_STBY_PLLAHVDDA_BMC_ADCVREFP1A_BMC_ADCVREFN1A_BMC_ADCREXT1P1V8_STBY_AVDDPLLP1V0_STBY_PE_VCC10AP1V8_STBY_PE_VCC18AP1V0_STBY_RC_VCC10AP1V2_STBY_MVDD_CKADCVREFEXT0ADCVREFEXT10.1UF25V10%X6SC0402CH5104KEB02ICAJ026000T06SMLFAST2600A3-GPCH5104KEB020.1UF 0.1UF25V25V25V
C132C131
C125C120
C113
H19
H18
H21
G21
M22
L22
K21
J21
V9
T9
W19
W18
W17
W16
T22
K12
K11
R22
P22
N22
H17
H16
H15
V6
U6
W14
W13
V13
U13
T13
R13
P13
N13
M13
L13
J12
H12
R12
P12
N12
J8
H8
F9
E9
F7
E7
H14
V10
T10
T6
R6
P6
L6
K6
J6
H6
G6
M6
W15
U18
U17
U16
U15
T21
T14
R21
R14
P21
P14
N21
N14
M21
M14
L21
L14
K19
K18
K17
K16
R10
R9
P11
P8
N11
N8
M11
M8
L10
L9
U21
V22
F20
F19
J9
V8
T8
AC21
W21
V21
V23
N5
AD17
AC20
AD18
AB20
AF17
AF19
AF18
AF20
Y21
AA21
R235
C76
C82 C84 C129 C127
C123
C124
C122C117C112C107C103C98
C118
C119C114
C108
C109
C104C99
C105C100
C91
C92C86
C93C87
C126
C115C110C101
C121C116C111C106C102
C94C88
C85
C95C89
C83
C77
L12
C75
R233
R234
C68C64C59
C74
C69
C72C70
C61
C66C62C58
C73C71C67
L11
C63
C56C54C52
L8
L10
C55
U5
1 2
1 2
1 2
1 2
5/6
1.8V RGM I/O
3.3V RGM I/OFSI(BUS 1-2)I3C(BUS 3-4)
3.3V I/O
VBATI2C / I3C
LPC / ESPI
SD2
SD1
MAC3 & MAC4
1.8V I/O
SLI
CORE
DDR
DP
PCIE-RC
PCIE-EP
PLL
I3C(Bus 1-2)
DAC
ADC
PV33D_RGM_K12
PV33D_RGM_K11
I3CVDDL2
I3CVDDL1
DPLLAVDD
PV33D_H15
I3CVDDH_F20
SD2VDD_H19
SD1VDD_H21
PV18D_R12
PV18D_P12
PV18D_N12
ADCVREFEXT1
ADCVREFEXT0
IV10D_R10
PV18D_RGM_J12
ADCAV33_AA21
PV18D_SLI_W14
PV18D_SLI_W13
PV18D_SLI_V13
PV18D_SLI_U13
PV18D_SLI_T13
PV18D_SLI_R13
PV18D_SLI_P13
PV18D_SLI_N13
PV18D_SLI_M13
PV18D_SLI_L13
BATVDD
PV33D_T22
PV33D_R22
PV33D_P22
PV33D_N22
PV33D_W19
PV33D_W18
PV33D_W17
PV33D_W16
PV33D_H17
PV33D_H16
PV18D_RGM_H12
PV18D_J8
PV18D_H8
PV18D_V6
PV18D_U6
IV10D_R9
IV10D_P11
IV10D_N11
IV10D_M11
IV10D_P8
IV10D_N8
I3CVDDH_F19 LPVDD
SD2VDD_H18
SD1VDD_G21
RVDD_K21
RVDD_J21
RVDD_M22
RVDD_L22
IV12D_U18
IV12D_U17
IV12D_U16
IV12D_U15
IV12D_T21
IV12D_R21
IV12D_P21
IV12D_N21
IV12D_M21
IV12D_L21
IV12D_T14
IV12D_R14
IV12D_P14
IV12D_N14
IV12D_M14
IV12D_L14
IV12D_K19
IV12D_K18
IV12D_K17
IV12D_K16
MVDD_CK
MVDD_T6
MVDD_R6
MVDD_P6
MVDD_L6
MVDD_K6
MVDD_J6
MVDD_H6
DP_VCC10A
DP_VCC18A
PE_VCC18A
PE_VCC10A
RC_VCC18A
RC_VCC10A
PLLDVDD_F9
PLLDVDD_E9
DACAV33_W21
PLLAVDD_F7
MVDD_G6
AVDDPLL
IV10D_M8
IV10D_L10
IV10D_L9
ADCREXT1
ADCVREFN1
ADCVREFP1
PLLAHVDD
PLLAVDD_E7
DACRSET
DACAV33_V21
ADCAV33_Y21
ADCVREFP0
ADCVREFN0
ADCREXT0
2
1
2
1
2
1
2
1
2
1
CAD NOTE:
2
1
2
1
2
1
2
1
2
1
2
1
2
1
2
1
2
1
2
1
2
1
2
1
2
1
2
1
2
1
2
1
2
1
2
1
2
1
2
1
2
1
2
1
2
1
2
1
2
1
2
1
2
1
2
1
2
1
2
1
2
1
2
1
2
1
2
1
2
1
2
1
2
1
2
1
2
1
2
1
2
1
2
1
2
1
21
2
1
21
21
2
1
2
1
2
1
2
1
2
1
2
1
2
1
2
1
2
1
2
1
2
1
2
1
2
1
2
1
21
2
1
2
1
2
1
2
1
21
21
2
1
SHEETDATE
DEPARTMENT
SIZE
PROJECT DOCUMENT NUMBER REV
REVIEWER
DESIGNER
123
7 3 2 1 6 5 4
E
A
B
C
E
D
C
B
A
7 6 5 4
D
OUTOUT
OUTOUT
IN
IN
IN
IN
IN
IN
IN
IN
IN
IN
C



I3C HIGH-VOLTAGE MODE SELECTIONPLLAHVDDAVDPLLI3C LOW-VOLTAGE MODE SELECTION
PE_VCC10A
ADC VREF
DACAV33RC_VCC18A
RC_VCC10ADP_VCC18ADP_VCC10A
Fri Aug 25 17:25:38 2023<NAME_2><NAME_1>NANANA17 OF 60BMC 6P5V_AUXP3V3_AUXP1V2_AUXP1V8_AUXP2V5_AUX
P3V3_AUXP1V0_AUXP1V0_AUXP1V8_AUXP1V0_AUX
P1V2_AUXP1V0_AUXP1V0_AUX
P1V2_AUX P1V2_AUXP2V5_AUXP1V8_AUX
P1V8_AUXP3V3_AUXP3V3_AUXP1V8_AUXP1V2_P1V0_I3C_VDDL1P1V2_AUXP1V2_P1V0_I3C_VDDL2PGPPA_BMC_AUXP1V8_AUXP3V3_P1V8_I2C_I3CP1V8_AUXDMG6968U-7LPC_ESPI_SEL_N0402LFCS31002FB080.1UFEMPTYCS41502FB04LPC_ESPI_SEL_R1%10KLPC_ESPI_SEL5%EMPTYEMPTYCS00003J9100603LF1/10W0PGPPA_BMC_AUX_LBAM1P020000SMLFNTR1P02LT1G1UFTMP_QCH5103K9B0016V10%25V1/10WIC33.2BLM18EG121SN1D/2ACX8EG1210000402IND16161616
16
16
16 16
161616
101127SMLFP3V3_STBY_DACAV330.1UFCH4104K1B00CX8PG121009SMLFCH5104KEB02P3V3_STBY_PLLAHVDDEMPTYIND1UF25V25VX6SC0402X7RBLM18PG121SN1D/2000MA1UFSMLFC040210%CHIPCS00002JB13AST2600A3-GPSMLFAJ026000T06
CS00002JB13BLM18PG121SN1D/2000MA00.01UF0.01UFC0402SMLFBLM18PG121SN1D/2000MAA_BMC_ADCVREFN0
1/16W
ICIND1/16W1/16W5%CX8PG121009X7R0402CH4104K1B000.1UFCS00003J9100EMPTY5%0603LFCHIP0402LF1/16W1%150KCS00002JB13EMPTY0CS00002JB130402LFEMPTY5%0CS00002JB130402LF1/16WEMPTY5%0CS00002JB130402LFCHIP1/16W5%00402LFCHIP1/16W5%0CS00002JB130402LF1/16WEMPTY5%0CS00002JB130402LFEMPTY00402LF5%CS00002JB130402LF1/16WEMPTY5%0CS00002JB130402LFCHIP1/16W5%0CS00002JB130402LF1/16WEMPTY00402LFCHIP1/16W5%0SMLFCH5104KEB02EMPTYEMPTYC040210UF20%X6S6.3VC0402 C0402
C0402C0402C0402C0402C0402
C0402 04020402
04020402
0402 04020402
04020402040204020402
04020402
0.1UF
0.1UF 0.1UF
0.1UF0.1UF0.1UF0.1UF10%10%10%
10%10% 10% 10%
10%10% 10%10% 10%10% 10%10% 10%10%10%10% 10%10%10%10%
10%10%10%X7RX7RX7RX7R
X7R X7R
X7RX7RX7RX7RX7RX7RX7R
X7R
50V50V
BLM18PG121SN1D/2000MACX8PG12100925VCH4104K1B00P1V8_STBY_AVDDPLLCH4104K1B00X6SADCVREFEXT0
P1V0_STBY_DP_VCC10AA_BMC_ADCVREFN1A_BMC_ADCVREFP1
ETERNAL REFERENCE VOLRAGE FORADC8-ADC15 (0.9V-2.7V)
CH4104K1B0025VCH4104K1B0025V
CH4104K1B0025VX6S1UF25VX6SCH5104KEB021UF25V
X6SCH5104KEB021UF25VBLM18PG121SN1D/2000MA25VCX8PG121009BLM18PG121SN1D/2000MASMLF25V 25VX6S1UF25VINDSMLFCH4104K1B00X6SINDCX8PG12100925VX6S25V1UF25V 25VX6SCH5104KEB021UF25VCH4104K1B0025VINDSMLF1UFCX8PG12100925VCH31006KB180.01UF0.01UF0.01UFCH5104KEB02SMLFIND1UF16VTMP_QCH5103K9B0025VBAM41410005ICCH4104K1B00
A_BMC_ADCVREFP0SMLFCH4104K1B00C0402P1V8_STBY_DP_VCC18ANTGS4141NT1GX6SPLACE CLOSE TO BMC PIN W1525V
0.1UF0.01UFCH31006KB18C0402X6S10%25VCH5104KEB02P1V0_STBY_RC_VCC10ABLM18PG121SN1D/2000MACH4104K1B00165%INDCX8PG121009CS00002JB130.1UF16CH5104KEB021UF0.1UF
CH4104K1B00ETERNAL REFERENCE VOLRAGE FORADC0-ADC7 (0.9V-2.7V)5%1/16W0402LFCH5104KEB02ADCVREFEXT1CH5104KEB020.1UFBLM18PG121SN1D/2000MASMLFCX8PG121009IND16P1V0_STBY_PE_VCC10A25V1UFP1V8_STBY_RC_VCC18ACH5104KEB02BLM18PG121SN1D/2000MACX8PG121009CH4104K1B00CH6101MEB01SMLFBAM69680000CHIP1/16W
SG
D
G
Y22
Y6
W25
W22
W12
W11
W10
W9
W8
W6
W5
V19
V18
V17
V16
V15
V14
V12
V11
V5
U23
U22
U19
U14
U12
U11
U10
U9
U8
U2
T19
T18
T17
T16
T15
T12
T11
T4
R25
R19
R18
R17
R16
R15
R11
R8
R2
P19
P18
P17
P16
P15
P10
P9
P4
N19
N18
N17
N16
N15
N10
N9
N6
N2
M19
M18
M17
M16
M15
M12
M10
M9
M4
L25
L19
L18
L17
L16
L15
L12
L11
L8
L2
K22
K15
K14
K13
K9
K8
K4
J19
J18
J17
J16
J15
J14
J13
J11
J2
H13
H11
H10
H9
H4
G25
G2
F21
F18
F17
F16
F14
F12
F10
F8
F6
E8
D25
C3
B23
B19
B15
B11
B5
AF26
AF4
AF1
AE23
AE20
AE17
AE13
AE9
AE6
AE3
AD4
AD1
AC25
AC6
AC2
AA22
AA20
AA19
AA15
AA14
AA10
AA8
AA7
AA6
AA3
AA1
A26
A5
A1
R493
3
L2
R784R782
R781 R783
R779 R780
C279C277 C282 C284
C270 C273
R716
R713
G
Q10
C224 C96
L17
C90
L15
C97
L16
C128 C130
C78
L13
C79
L14
C80 C81
C48
L7
C51
L9
C60 C65
R232
C53 C57
R231
C47 C50
L6
C46
L5
C49
C136
C138
C137
C135
C134
C133
R278
C139
C140
R279
R280
R281
S D65 421S D
Q4
U5
Q5
G
6/6
GND_U23
GND_AA20
GND_P19
GND_P18
GND_P17
GND_P16
GND_P15
GND_P10
GND_P9
GND_P4 GND_AF26
GND_AF4
GND_AF1
GND_AE23
GND_AE20
GND_AE17
GND_AE13
GND_AE9
GND_AE6
GND_AE3
GND_AD4
GND_AD1
GND_AC25
GND_AC6
GND_AC2
GND_AA22
GND_AA19
GND_AA15
GND_AA14
GND_AA10
GND_N19
GND_N18
GND_N17
GND_N16
GND_N15
GND_N10
GND_N9
GND_N6
GND_N2
GND_M19
GND_M18
GND_AA6
GND_AA7
GND_AA8
GND_AA3
GND_AA1
GND_Y22
GND_Y6
GND_W25
GND_W22
GND_M17
GND_M16
GND_M15
GND_M12
GND_M10
GND_M9
GND_M4
GND_L25
GND_L19
GND_L18
GND_W12
GND_W11
GND_W10
GND_W9
GND_W8
GND_W6
GND_W5
GND_V19
GND_V18
GND_V17
GND_V16
GND_V15
GND_V14
GND_V12
GND_V11
GND_V5
GND_U22
GND_U19
GND_U14
GND_U12
GND_U11
GND_U10
GND_U9
GND_U8
GND_U2
GND_T19
GND_T18
GND_T17
GND_T16
GND_T15
GND_T12
GND_T11
GND_T4
GND_R25
GND_R19
GND_R18
GND_R17
GND_R16
GND_R15
GND_R11
GND_R8
GND_R2
GND_L17
GND_L16
GND_L15
GND_L12
GND_L11
GND_L8
GND_L2
GND_K22
GND_K15
GND_K14
GND_K13
GND_K9
GND_K8
GND_K4
GND_J19
GND_J18
GND_J17
GND_J16
GND_J15
GND_J14
GND_J13
GND_J11
GND_J2
GND_H13
GND_H11
GND_H10
GND_H9
GND_H4
GND_G25
GND_G2
GND_F21
GND_F18
GND_F17
GND_F16
GND_F14
GND_F12
GND_F10
GND_F8
GND_F6
GND_E8
GND_D25
GND_C3
GND_B23
GND_B19
GND_B15
GND_B11
GND_B5
GND_A26
GND_A5
GND_A1
3
1 2
GATE
12
1 2
1 2
1 2
1 2
1 2
1 2
1 2
1 2
S D54261DRAINSOURCE
2
1
2
1
CAD NOTE:
CAD NOTE:
CAD NOTE:
21
21 2 1
2
1
2
1
2
1
2
1
2
1
2
1
21
2
1
2
1
2 1
2
1
21
2
1
21
2
1
2
1
2
1
21
2
1
21
2
1
2
1
2
1
21
2
1
21
2
1
2
1
21 2
1
2
1
21
2
1
2
1
21
2
1
21
2
1
21
21
21
21
21
21
21
2
1
2
1
21
21
21
SHEETDATE
DEPARTMENT
SIZE
PROJECT DOCUMENT NUMBER REV
REVIEWER
DESIGNER
123
7 3 2 1 6 5 4
E
A
B
C
E
D
C
B
A
7 6 5 4
D
OUT OUT
IN
OUT OUT
OUT OUT
OUT
OUT
OUT
OUT
IN
IN
IN
IN
R646
R645
C



Fri Aug 25 17:25:38 2023<NAME_2><NAME_1>NANANA18 OF 60BMC_PHY_BCM54612E 1/2
SHEETDATE
DEPARTMENT
SIZE
PROJECT DOCUMENT NUMBER REV
REVIEWER
DESIGNER
123
7 3 2 1 6 5 4
E
A
B
C
E
D
C
B
A
7 6 5 4
D
C



Fri Aug 25 17:25:39 2023NANA19 OF 60NA<NAME_2><NAME_1>BMC_PHY_BCM54612E 2/2
SHEETDATE
DEPARTMENT
SIZE
PROJECT DOCUMENT NUMBER REV
REVIEWER
DESIGNER
123
7 3 2 1 6 5 4
E
A
B
C
E
D
C
B
A
7 6 5 4
D
C



R337 STUFFR3 = 0 OHM STUFFR1 UNSTUFFR2 STUFFFOR TWIN DIE PART:R1 STUFFR2 UNSTUFFFOR SINGLE DIE PART:(DEFAULT)R3 = 240 OHM(1%) STUFFSINGLE/TWIN DIE SELECTIONFri Aug 25 17:25:39 2023<NAME_2><NAME_1>NANANA20 OF 60M_BMC_DDR4_MCLK_DNBMC DDR4 SDRAM
P1V2_AUXP1V2_AUXP2V5_AUX
P1V2_AUXP1V2_AUXP1V2_AUX
P0V6_DDR_VREF_AUXP0V6_DDR_VREF_AUXM_BMC_DDR4_ZQUEMPTY0CS00002JB130M_BMC_DDR4_MBG112200402LFCS21002FB060.1UF10%50V0.01UFCS06042FB03M_BMC_DDR4_ALERT_NM_BMC_DDR4_MBG1M_BMC_DDR4_MCKEM_BMC_DDR4_MODTM_BMC_DDR4_MBA1M_BMC_DDR4_MBA0M_BMC_DDR4_MBG0M_BMC_DDR4_MACT_NM_BMC_DDR4_MCS_NM_BMC_DDR4_MRAS_NM_BMC_DDR4_MCAS_NM_BMC_DDR4_MWE_NCHIP120CHIPCHIPCS11202FB021/16W1201201204.7KEMPTYCHIP120EMPTY0.22UFEMPTY 0.22UFCS00002JB131/16WM_BMC_DDR4_BG10402LF CHIP20X7R10%CS21002FB06PD_M_BMC_DDR4_PARPD_M_BMC_DDR4_TENM_BMC_DDR4_ALERT_NPD_M_BMC_DDR4_ZQM_BMC_DDR4_DQS0_NM_BMC_DDR4_DQS0_PM_BMC_DDR4_RST_N100PF50V5%NPO0402CH11006JB000.1UF25V10%X7R04020.1UFCH4104K1B000.1UF25V10%0.1UFM_BMC_DDR4_BG1C0402C0402C0402C0402C0603CH5474KE906M_BMC_DDR4_MCS_NM_BMC_DDR4_MRAS_NM_BMC_DDR4_MCAS_N04025%1%20CHIPCHIP120CHIP120CHIPCHIPCHIPCHIPCHIP1220CH31006KB18CH4104K1B0025VCHIP00402X7R10%X7R
CHIP
M_BMC_DDR4_ZQUCH5104KEB02CS21002FB060.01UFCH31006KB18CHIP120120CHIP120CS12402FB011/16W1%121220
1212122012201212121212201220122012201220122012201220122012201220 122012201220122012201220
20 122012201220121220122020 122012201220M_BMC_DDR4_MCLK_C
M_BMC_DDR4_MDM1M_BMC_DDR4_MDM0M_BMC_DDR4_MCLK_DPM_BMC_DDR4_MCLK_DNM_BMC_DDR4_DQS1_PM_BMC_DDR4_DQS1_NM_BMC_DDR4_MCKEM_BMC_DDR4_MWE_NM_BMC_DDR4_MODTM_BMC_DDR4_MACT_NM_BMC_DDR4_MBG0M_BMC_DDR4_MBA0M_BMC_DDR4_MBA1M_BMC_DDR4_MA[13:0]M_BMC_DDR4_DQ[15:0]M_BMC_DDR4_MA[13:0]CH4104K1B000.1UF25VX6S1UF10%25V10%X6S1UF25V1UF25V10%X6S4.7UF25V10%X6SC0402X7R10%C0402X7R10%X7R0.1UF10%25VX6S1UF10%25VX7RCH4104K1B0010%25V10%25VX7RSMLFK4A8G165WC-BCTDAKD5FGUT502IC X7R0.1UF10%25VX7R0.1UF10%25V0.1UF25V X7R0.1UF10%25VX7RCH4104K1B000.1UF10%25VX6S10UF20%C04026.3VX6SCH6101MEB0110UF20%C04026.3VCH4223K1B0050V04020402040204020402040204020402
EMPTY5%1/16W0402LFCS00002JB13
120CHIP120CHIP1201%0402LF120120120120CHIP120CHIP120CHIP120CHIP120120CHIP120120CHIP120CHIP120CHIP120CHIPCHIPCHIP1201%1/16WCHIP0402LFCS11202FB02120CHIP120CHIP120CHIP120CHIP120CHIP120CHIP120CHIP120120120CHIP120CHIP120CHIP120CHIP120CHIP120CHIP120CHIP120CHIP120CHIP120CHIP120CHIP120CHIP1201%1/16WCHIP0402LFCS11202FB021K1%1/16WCHIP0402LF1K1%1/16WCHIP0402LF240CHIP0402LF1K1%1/16W1K1/16WCHIP0402LF1%1/16WCHIP0402LFCS24702FB0660.4 CHIPM_BMC_DDR4_MCLK_DP60.4 CHIP
0402
C221 C222 C225
F9
L2
H9
H1
F1
E8
E3
D8
D2
C9
A8
A2
T1
N1
M9
K9
K1
G8
E9
E1
B2
M1
R9
B1
J8
J2
G9
G1
F8
F2
D9
C1
A9
A1
T9
R1
L9
L1
J9
J1
G7
D1
B9
B3
N9
P1
L8
T3
K3
T7
D7
D3
C8
C2
C7
C3
B8
A3
B7
A7
G3
F3
J7
J3
H8
H2
H7
H3
F7
G2
E2
E7
L7
K2
K7
K8
M8
M2
N8
N2
P9
L3
T8
M7
T2
M3
R7
R2
R8
P2
P8
N3
N7
R3
P7
P3
U1
R351R326
C18
C17
C14
C13
R352
R353
R355
R354
R356
R357
R358
R327
R328
R329
R330
R331
R333
R332
R359
R360
R362
R361
R363
R364
R334
R335
R336
R337
R338
R339
R6R5R4
R365
R366
R367
R368
C15
R369
R370
R371
R372
R373
R374
R341
R340
R343
R342
R344
R346
R345
R348
R347
R349
R375R350 C16
R9
C229
C12
R7
R8
C10
C169
C170C168
R324
R325
C9C7C5
C8C6
R3
R1
R2
C4C3C2C1
7
4
5
0
1
2
1
0
4
3
7
6
5
9
8
12
11
10
14
13
15
3
2
8
7
6
9
10
13
12
11
0
1
4
3
2
5
8
6
11
10
9
12
13
RESET_n
DMU_n||DBIU_n
DML_n||DBIL_n
VSSQ9
VSSQ8
VSSQ7
VSSQ6
VSSQ5
VSSQ4
VSSQ3
VSSQ2
VSSQ1
VSSQ0
VSS8
VSS7
VSS6
VSS5
VSS4
VSS3
VSS2
VSS1
VSS0
VREFCA
PAR
TEN
DQSL_c
DQSL_t
DQSU_c
DQSU_t
CK_c
CK_t
DQU7
DQU6
DQU5
DQU4
DQU3
DQU2
DQU1
DQU0
DQL7
DQL6
DQL5
DQL4
DQL3
DQL2
DQL1
DQL0
ZQ
WE_n||A14
VPP1
VPP0
VDDQ9
VDDQ8
VDDQ7
VDDQ6
VDDQ5
VDDQ4
VDDQ3
VDDQ2
VDDQ1
VDDQ0
VDD9
VDD8
VDD7
VDD6
VDD5
VDD4
VDD3
VDD2
VDD1
VDD0
RAS_n
ODT
NC1
CKE
CS_n
CAS_n||A15
BG0
BA1
BA0
ALERT_n
ACT_n
A9
A8
A7
A6
A5
A4
A3
A2
A13
A12||BC_n
A11
A10||AP
A1
A0
2
1
2
1
2
1
2121
2
1
2
1
2
1
2
1
21
21
21
21
21
21
21
21
21
21
21
21
21
21
21
21
21
21
21
21
21
21
21
21
21
212
1
2
1
2
1
21
21
21
21
2
1
21
21
21
21
21
21
21
21
21
21
21
21
21
21
21
21
2121
2
1
21
21
21
21
21
2
1
2
1
2
1
2
1
2
1
2
1
2
1
2
1
2
1
21
21
21
2
1
2
1
2
1
2
1
SHEETDATE
DEPARTMENT
SIZE
PROJECT DOCUMENT NUMBER REV
REVIEWER
DESIGNER
123
7 3 2 1 6 5 4
E
A
B
C
E
D
C
B
A
7 6 5 4
D
OUT
OUT
OUT
OUT
OUT
OUT
BI
BI
ININ
ININBIBIBIBI
BI
INININ
ININ
ININ
IN
BI
IN
IN
IN
BI
IN
BI
ININ
OUT
OUT
OUT
OUT
OUT
OUT
IN
OUT
C



MOVE BMC FLASH TO BSM_20220214
Fri Aug 25 17:25:39 2023<NAME_2><NAME_1>NANANA21 OF 60BMC - BSM CONNECTOR
P3V3_AUXP3V3_AUXP3V3_AUXP3V3_AUXP3V3_AUXP3V3_AUXP3V3_AUX
P3V3_AUXBMC_EMMC_DT7BMC_EMMC_DT433.2EMPTY33.2EMPTY33.233.2EMPTYEMPTYEMMC_WPRST_SPI_BMC_FLASH_R1_NRST_SPI_BMC_FLASH_R2_NCHIP33.2CHIPBMC_EMMC_CLKBMC_EMMC_CMD33.233.233.2EMPTYEMPTYEMPTY33.2EMPTYEMPTYEMPTY 33.2EMMC_CMD_R211%10K1%SMLFEMPTYCHIP0BSM_PRSNT_R_N34 15IOEMMC_DT1_REMMC_CLK_R10K10KCHIP10K
25V040210%0.1UF
2121212136 3412121321 1312212121
21 121212121221122112EMMC_DT3_REMMC_DT2_RCS31002FB08CHIP21EMMC_CMD_R463421CH4104K1B0025V10%20%EMPTY EMPTY EMPTY0.1UF
0402LF46 362110K10KTMP_QCS31002FB261%0402LFEMPTYEMPTYEMPTYEMPTY122121DFHS75FR1332525TMP_QCS21002FB241KEMPTY1K21211327271313252513SPI_BMC_BT_WP1_N_RSPI_BMC_BT_WP0_N_R1327TMP_QCS21002FB24EMPTYSPI_BMC_CS1_FLASH_R_NSPI_BMC_CS0_FLASH_R_N21BSM_PRSNT_N
CH6222M990122UF10V0402C0603
EMPTYBMC_EMMC_DT6BMC_EMMC_RST_NBMC_EMMC_DT5SMB_BMC_MM16_R5_SDASMB_BMC_MM16_R5_SCL21131%4.7KCHIP0402LF1/16W0402LF0402LFSCONN67_NASA0-S6730-TS67SPI_BMC_BOOT_CS0_R_NCHIP33.2SPI_BMC_CLK_FLASH_RSPI_BMC_IO0_FLASH_RSPI_BMC_IO1_FLASH_RRST_SPI_FLASH_BUF_NSPI_BMC_BOOT_MISO33.2CHIPRST_SPI_FLASH_BUF_N33.2EMPTY33.233.2CHIP33.21/16W1%1/16WCHIPCHIP1%4.7K 4.7K1%4.7K0402LF1/16WEMPTYBMC_EMMC_DT012BMC_EMMC_DT3BMC_EMMC_DT1BMC_EMMC_DT233.2SPI_BMC_BOOT_CS1_R_NSPI_BMC_BOOT_CLKSPI_BMC_BOOT_MOSICHIPCS03322FB03CHIP33.2SPI_BMC_HOLD0_NEMPTY4.7K 4.7K10K10K10K1/16WEMPTYEMMC_DT0_REMMC_DT2_REMMC_DT1_REMPTYEMPTYEMPTYEMMC_DT6_REMMC_DT7_R21BMC_EMMC_RST_N10KEMPTYEMMC_DT3_REMMC_DT4_REMMC_DT5_R2133.21KEMMC_DT4_REMMC_DT0_REMMC_DT5_REMMC_DT6_REMMC_DT7_RSMB_BMC_MM16_R1_SDASMB_BMC_MM16_R1_SCLSPI_BMC_HOLD1_N
R90
R561
R562
R552
R550
R549
R547
R553
R558 R557
R11
R404
R867
R849
R850
R543 R664 R665
R652
R653
R650
R651
G2G1
7574
7372
7170
6968
6766
6564
6362
6160
5958
5756
5554
5352
5150
4948
4746
4544
4342
4140
3938
3736
3534
3332
3130
2928
2726
2524
2322
2120
1918
1716
7
6 5
4 3
2 1
C234 C235
R655
R656
R659
R657
R658
R660
R661
R663
R662
R532
R647
R648
R649
R48
R654
C228
J4
KEY
G2G1
75
73
71
69
67
65
63
61
59
57
55
53
51
49
47
45
43
41
39
37
35
33
31
29
27
25
23
21
19
17
7
5
3
1
74
72
70
68
66
64
62
60
58
56
54
52
50
48
46
44
42
40
38
36
34
32
30
28
26
24
22
20
18
16
6
4
2
2
1
21 21
21 21
21
21 21
2
1
2
1
2
1
2
1R58
21R57
2
1
21
2
1
21 21
2
1
2
1
21 21
21 21
2
1
2
1
21 21
21
21 21
21 21
21 21
21
21 21
21
21
21
2
1
SHEETDATE
DEPARTMENT
SIZE
PROJECT DOCUMENT NUMBER REV
REVIEWER
DESIGNER
123
7 3 2 1 6 5 4
E
A
B
C
E
D
C
B
A
7 6 5 4
D
ININ
ININ
OUTOUTOUTOUTOUTOUTOUT
OUTOUT
IN
OUT
INBI
ININ
OUT
BIBI
ININ
BI
IN
BI
ININININ
BIBI
BI
BI
BIBI
BIBI
IN
INININ
C



TO BMC (EXTRST_N)TO BMC (SRST_N)OPEN-DRAINTO BMC TPM
OPEN-DRAINFROM CPLDFROM BMC WDTRST1#TO BMC (SRST_N)FROM PWRGD_PSU_AC_PWROKFROM DELAY IC FOR VR PGFROM CPLD FOR SRST#DAMPING RES SHOULD CLOSE TO BUFFEROPEN-DRAINADD U58_20221206
Fri Aug 25 17:25:40 2023<NAME_2><NAME_1>NANANA22 OF 60RESET CIRCUIT
I14P3V3_AUXP3V3_AUXP3V3_AUXP3V3_RGMP3V3_AUXP3V3_AUXP3V3_AUX
P3V3_RGMP3V3_AUXP3V3_AUXP3V3_AUXP3V3_AUXP1V0_AUXSMLF10%PWRGD_P1V0_AUX_DELAY_BUFRST_SRST_PLD_BMC_BUF_NC04021/16W1%RST_SRST_PLD_BMC_R1_NPWRGD_P1V0_AUX_DELAYPWRGD_PSU_AC_PWROKRST_BMC_HW35RST_BMC_SELF_HW_R3CS00002JB130CHIP10RST_SRST_PLD_BMC_R_N222813EMPTY3413351K1%1/16WEMPTY1%1/16W1K0402LF25VMC74VHC1G32DTT1GCH4104K1B00
PWRGD_P1V0_AUX_DELAY_R1
SDMK0340L-7-FX7RIC470KCHIPCHIP0402LFPWRGD_P1V0_AUXIC100KCH4104K1B000402X7R10%0.1UF15221534
225636
46
IC5% 1001%1/16W 0402LFRST_BMC_SRST_NEMPTY25V10%0.1UFCH4104K1B000402RST_EXTRST_N5%
1%2K
CS24702FB060402LFCHIP1/16W1%4.7KCS34702FB01BJT_Q3_B0402LFCHIP1%47KCS14992FB060402LFCHIP1/16W1%499
CHIP
10KCHIP1/16W1%
25V
BJT_Q3_CSMLFICMMBT3904-7-FCHIP1/16W0IC
SMLFCHIPCS11002FB070402LF49.91/16WCS31002FB080402LFSMLF
1/16WCHIPCS22002FB070402LFPWRGD_P1V0_AUX_DELAYPWRGD_P1V0_AUX_R21%1/16WCHIPAL003808005
CS00002JB13X7R100K25VU43_CT0402X7R10%0.1UF0402LF0402LF0402CH4104K1B00BA0390400H0MMBT3904-7-FBA0390400H0CS00002JB130402LFRST_BMC_EXTRST_R2_N0CS00002JB130CHIP01/16W34011 MC74VHC1G07DFT2GAL001G07003SMLFEMPTY2KCHIP1%05%EMPTY25V10%EMPTYCH2474K1B08RST_BMC_EXTRST_R1_N0402LFRST_BMC_SRST_BUF_R1_NCS00002JB1325VEMPTYRST_BMC_SRST_NICBAM138K0000BSS138KBSS138KSMLF0402LF0.1UF151UF25V2233.2040210%SMLF1/16WAL002G0700374LVC2G07DW-70.1UFX6SCHIPCS44702FB02ICRST_BMC_HW_OUTRST_BMC_HW_R1BC000340033CH5104KEB02RST_BMC_SELF_HW_D1%100K4700PRST_BMC_SELF_HW_D_C2200PF50V0402X7R10%TMP_QCH22206KB160402LFCS41002FB09CHIP1/16WC040210%1/16W1%CHIP0RST_BMC_SELF_HWEMPTY0402LFCS00002JB134.7KEMPTY5%AL001G320311/16WCS22002FB070402LF1/16WCHIP49.91/16WCS04992FB071%RST_BMC_SRST_BUF_R_NCHIP0402LFCS41002FB09CS41002FB09CH4104K1B00TPS3808G01DBVR
OVT
G
S DC173
R887
R888
5
4
1
2
3
R388
6
52
4
1
3
5
4
1
2
3
52
43
61
R633
R125
R108
C264
C253
R710
R711
C223
C34
R192
R614
21
C147
B
B
CECE
U58
U43
U13
U6
D17
U12
Q3
Q1
VCC
GND
IN_A
IN_B
OUT_Y
SENSE
CT
VDD
#MR
GND
#RESET
NC1
OUT_YGND
IN_A
VCC
VCCGND
2Y
1Y
2A
1A
1
1 2
1
3232
2
1
2
1
2
1
2
1R450
2
1 R282
2
1
21
2
1
21
21
21
2
1
2
1
2
1
21
21
21
2
1
21
2
1
2
1
2
1
21
21
2
1
2
1
2
1
21
2
1
21
2
1
2
1
SHEETDATE
DEPARTMENT
SIZE
PROJECT DOCUMENT NUMBER REV
REVIEWER
DESIGNER
123
7 3 2 1 6 5 4
E
A
B
C
E
D
C
B
A
7 6 5 4
D
IN
IN
OUT
IN
OUT
IN
IN
OUT
IN
OUT
OUT
C337
R751
R451
R49
R315
R124
R313 R314
C161
R106
R636
R291
R290
R289R287
C



R84,R85 CHANGE FROM 33 TO 0_20230314CAD NOTE:PLACE CLOSE TO VGA CONNC6 CLOSE TO U1L3C5 CLOSE TO U1L2CAD NOTE:CHANGE TO 15PF_20221221DDC SMBUS ISOLATORSPLACE FILTER CIRCUIT CLOSE TO VGA CONNCHANGE TO 22,18,22PF_20221221Fri Aug 25 17:25:40 2023<NAME_2><NAME_1>NANANA23 OF 60BMC VIDEO(FRONT VGA)CRT_VCC5P3V3_RGMP3V3_RGM
CRT_VCC5P5V_AUX
P5V_AUXP5V_AUXCRT_VCC5
P5V_AUX
CRT_VCC5CRT_VCC55%CHIP5%V_VGAVS_BUF_RV_BMC_LS_DDC_SCLV_BMC_LS_DDC_SDAV_VGAHS_BUF_RCHIPBLM18BB470/500MABLM18BB470/500MABLM18BB470/500MACX8BB47000750VC0GTMP_QCH02206JB08040222PFV_BMC_DDC_LS_GATEBAM7002004710%CS11502FB0715PF0402CX8BB470007SMLF0074HC1G126GWICBMC_DDC_BUF_PWRV_VGAVSV_VGAHSSMLF0.1UF04020.1UF25VX7R4.7K150402NPO5%5%0402C0G0402040215PF50V5%50V15PF5%V_DACR150V_DACG5%C0G0V_BMC_LS_DDC_SDAV_BMC_LS_DDC_SCL235%0402LFCHIP2.2K1%1500402LF1/16W1%150IC
V_BMC_DDC_SCLNPO NPO040210PF 10PF50V50VCS11502FB07V_VGAVS_BUFDFHD13MS080IOSMLF
ICDT1240E-04LP-7SMLFV_BMC_LS_DDC_SCL_RV_BMC_LS_DDC_SDA_RV_DACG_IOV_DACB_IOSMLFBZA462AEMPTY50V1%100PF5%100PF50V5%
0603LFEMPTY
040225V10%X7RIC
ICSMLFSS0530BCSS0530Z0016V10%SMLFV_BMC_DDC_SDA
0CHIP5%0
1/16WCHIP0402LF
EMPTY5%0CS00003J910SMLFIC
CHIP
DT1240E-04LP-7BC001240Z01
V_DACR_IOCHIPEMPTY04020402EMPTY
BC001240Z01V_VGAHS_BUFV_VGAVS_BUF2.2K0402V_DACB_IO
SMLF1%
TP42N7002KDWIC1%232323
2323232323
151515 2323 232315 23232315150603EMPTY
23V_DACR_IOV_DACG_IO23DK110TPU003EMPTY1.1A/8VSMLFEMPTYBCSBA130Z00SMLFSBA130Q
CHIP1UFBCSS0530Z00SS0530SMLF1/16WBAM700200472N7002KDWCRT_VCC5_2_D CRT_VCC5_2_FUSEV_BMC_LS_DDC_SCL_RV_BMC_LS_DDC_SDA_RV_VGAHS_BUFSCONN13_50228-0130C-V01
2.21KEMPTY2.21KBCZA462AZ01EMPTYTP_ESD_VGA_P40402LFCHIP33.233.2CHIPBMC_DDC_BUF_ENSMLF74HC1G126GWAL1G0126007V_DACBSMLFIND1/16WCS11502FB070402LF0402LF4.7K1%0402LFCHIP1/16W5%1/16WCHIP1/16WCHIP1%CX8BB470007IND1/16WCHIP0402LFTMP_QCH02206JB08NPO5%22PF50VSMLFIND18PF50VC0G50V
D1S1
S2 D2
G1G2
3 state output
3 state output
C210C208
21
21
21
G2
G1
13
12
11
10
9
8
7
6
5
4
3
2
1
21
8
3
10
9
7
6
5
4
2
1
8
3
10
9
7
6
5
4
2
1
21
R28
C214C213C212
R16
R17
C211
R89
R92R91
R84
R85
R88R87C209
R86
R32
C204
D9
D11
R27
R30
R29
U26
U33
C207
R31
C206C205
R18
C203C202
D12
Q2Q2
L30
L29
L28
J8
D16
U34 U35
FS1
CA
CA
GND
5
42
GND
5
42
1 2
1 2
1 2
G2
G1
13
12
11
10
9
8
7
6
5
4
3
2
1
CA
NC2
IO4
IO2
NC4
NC3
VSS2
NC1
IO3
VSS1IO1
NC2
IO4
IO2
NC4
NC3
VSS2
NC1
IO3
VSS1IO1
21
643152
11
2
1
2
1
21
2
1
2
1
2
1
21
21
2
1
2
1
2
1
2
1
21
21
2
1
2
1
1 6
2
1
21
2
1
2
1
CA
CA
21
2
1
21
3
5
42
3
5
42
2
1
2
1
2
1
2
1
21
2
1
2
1
4 3
65 4321
2 115
SHEETDATE
DEPARTMENT
SIZE
PROJECT DOCUMENT NUMBER REV
REVIEWER
DESIGNER
123
7 3 2 1 6 5 4
E
A
B
C
E
D
C
B
A
7 6 5 4
D
OUT
BI
OUT
OUT
OUT
OUT
OUT
BI
OUT
BI
IN
BI
IN
IN
IN
IN
IN
IN
IN
IN
IN
BIIN
IN
IN
C



REMOVE DISPLAY PORT FUNCTION FROM DVT.
Fri Aug 25 17:25:40 2023<NAME_2><NAME_1>NANANA24 OF 60BMC VIDEO(REAR DP)
SHEETDATE
DEPARTMENT
SIZE
PROJECT DOCUMENT NUMBER REV
REVIEWER
DESIGNER
123
7 3 2 1 6 5 4
E
A
B
C
E
D
C
B
A
7 6 5 4
D
C



OPEN-DRAINFri Aug 25 17:25:41 2023<NAME_2><NAME_1>NANANA25 OF 60BMC ROM
P3V3_AUXP3V3_AUXP3V3_AUX
P3V3_AUX
P3V3_AUX
P3V3_AUXRST_SPI_FLASH_N
FLASH_R_WP_STATUSCHIP2121CH4104K1B00RST_SPI_FLASH_R_N0402LFCS24702FB06CHIP1%SPI_BMC_BT_WP1_N_RSPI_BMC_BT_WP0_N_R33.2CHIP33.2FLASH_LATCH_Q_N_R133.2CHIPFLASH_LATCH_Q_N_R1333.2FLASH_WP_STATUSCHIP0FLASH_LATCH_CPCHIP1/16W2513BMC_RSTIND_NCHIP33.2RD_NFM_FLASH_LATCH_N1%4.7K1/16WCHIP0402LF4.7K1%0402LFCHIP1/16WNC_J1_P3PU_J1_P10402CH4104K1B00AL001G14017FLASH_LATCH_Q_N_R2SMLFSN74LVC1G14DCKR10%X7RCH4104K1B0025V1525FM_FLASH_LATCH_N10%X7R04020.1UF5%0402LF0CS00002JB13SMLFIC74LVC1G74DPAL1G0074K01CHIP4.7K1%EMPTYFLASH_LATCH_DNC_U54_P1
25V33.215
13
2110%33.20402CHIPX7RRST_SPI_FLASH_BUF_NCHIP4.7KSMLFIOSCONN3_212-H91-03GBR1DFHD03MS1610.1UF25V5%0CHIP1/16W0402LFCS00002JB13ICNC_U55_P1
SMLFICAL1G0007016SN74LVC1G07DCKRRST_SPI_FLASH_BUF_R3_N0.1UF
R560
R559
R556
R555
R551
R548
R592
R181
3
2
1
C313
4
5
13
2
C312
R182
8
7
6
3
5
4
2
1
R827R752
C304
4
5
13
2
R563
J1
U55
U54
U44
NC1
Y
GND
A
VCC
1
2
3
NC
Y
GND
A
VCC
Q
SD_N
RD_N
VCC
GND
Q_N
D
CP
21
21
21
21
21
2
1
2
1
2
1
2
1 2
1
2
1
21
21
R545
2121
2
1
2
1
SHEETDATE
DEPARTMENT
SIZE
PROJECT DOCUMENT NUMBER REV
REVIEWER
DESIGNER
123
7 3 2 1 6 5 4
E
A
B
C
E
D
C
B
A
7 6 5 4
D
OUTIN
OUT
OUT
OUT
IN
IN
OUT
R554
C



CHANGE TO 150OHM_20220804EEPROM ADDRESS: 0XA0
CHANGE TO HEADER_20220804DUMMY FOOTPRINT FOR REMOTE TEMP SENSOR ASSEMBLESMBUS ADDRESS 0X96
Fri Aug 25 17:25:41 2023<NAME_2><NAME_1>NANANA26 OF 60EEPROM & TEMP SENSOR
P3V3_AUXP3V3_AUXP3V3_AUXP3V3_AUXCS24702FB061K1%CHIP0402LFSMB_TMP421_BMC_MM2_SCLCONN8_TSW-104-07-F-DCH4104K1B000402X7R4.7K1/16WTMC75_A0DFHD08MS225THLF10%CS04992FB0749.949.9SMB_TMP421_BMC_MM2_SDASMB_BMC_ALERT16_R_NCS21002FB060402LFTMC75_A2SMB_BMC_MM2_SDACHIP12271010 1227CHIPSMB_BMC_MM2_SCLSMB_BMC_ALERT16_NCHIP1527 3510KCS31002FB08TMC75_A1EMPTYCS11502FB0715033.2SMB_BMC_MM16_SCLSMB_BMC_MM16_R2_SCLCHIP1K1%1/16WCS21002FB061/16WSMB_BMC_MM16_R2_SDACH4104K1B000402X7R10%25VCHIPCS11002FB070402LF0402LF1/16WCHIPCS24702FB060402LF121227274.7K1%4.7KEMPTYCHIP1/16WSMB_BMC_MM16_SDAEMPTY1/16W0402LF1%1/16W0402LF1/16W1%1%4.7K0402LF100CHIP0.1UF1%1001%1/16W0402LF1/16WCHIP1K0402LFCS21002FB061%1/16WCHIP100
0.1UF25VCHIP0402LF1%4.7K1/16W4.7K1%1K1%EMPTY1/16WFRU_E20402LFEMPTY1%FRU_E0FRU_E10402LFCS24702FB06EMPTYPD_FRU_WC_NICAKE30Z0K610M24128-BWDW6TPSMLFEMPTY
87
65
43
21
R420
R52
R53
R409
R410
C191
R416R418
R417R419
R421
R15
C192
7
4
8
5
63
2
1
U19
R14
R413
R13R12
R412R411
J14
2
4
1
3
87
65
E0
E1
E2
VSS SDA
SCL
WC#
VCC
21
2
1
2
1
21 R54
21
21
2
1
2
1
2
1
2
1
2
1
21
2
1
2
1
2
1
2
1
2
1
2
1
2
1
SHEETDATE
DEPARTMENT
SIZE
PROJECT DOCUMENT NUMBER REV
REVIEWER
DESIGNER
123
7 3 2 1 6 5 4
E
A
B
C
E
D
C
B
A
7 6 5 4
D
OUT
IN
BI
INBI
C



CHANGE TO CS21802FB02 1.8K_20230314CHANGE TO 400OHM_20230421CHANGE TO 500OHM_20221206CHANGE TO 10KOHM_20221222STRAP VALUE=STRAP VALUE=BALLUART_BMC_5_TXD_RC8STRAP NET NAMEPU/PDINTERNALPDINPUT LEVELPU(P3V3_RGM)1PUENABLE BMCDESCRIPTIONSTRAP VALUE = INVERSE OF INPUT0(DEFAULT)DISABLE BMCBIT 0 (DEDICATED STRAP PIN)BALL NAME: FWSPICS0#SIGNAL NAMENUMBERDISABLE CPU BOOTCHANGE TO 10KOHM_20221222
Fri Aug 25 17:25:41 2023<NAME_2><NAME_1>NANANA27 OF 60BMC HW STRAPS & MISC
P3V3_AUXP3V3_AUXP3V3_AUX P3V3_AUXP3V3_AUX
P3V3_RGMP3V3_AUX
P3V3_AUXP3V3_AUX4021212SMB_BMC_MM2_SCLSMB_BMC_MM1_SDACHIPSMB_BMC_MM3_SDACHIPCHIPCHIPCHIPSMB_BMC_MM3_SCLCHIPSMB_BMC_MM4_SDASMB_BMC_MM5_R_SCLSMB_BMC_MM5_R_SDASMB_BMC_MM6_SCLCHIPSMB_BMC_MM7_R_SCLSMB_BMC_MM8_SCLSMB_BMC_MM8_SDASMB_BMC_MM9_SCLSMB_BMC_MM9_SDASMB_BMC_MM10_SCLSMB_BMC_MM10_SDA2.2K2.2K10K2.2K2.2K1.8K2.2KSMB_BMC_MM1_SCL1.8K CHIP2.2K2.2KCHIPCHIPCS14992FB06SMB_BMC_MM4_SCL1228351315SMB_BMC_ALERT10_NFM_ME_BT_DONEVOL_SEN_ALERT_R34131226262810351335351535SMB_BMC_ALERT12_NSMB_BMC_ALERT9_NSMB_BMC_ALERT4_NSMB_BMC_ALERT3_NCHIP35EMPTYEMPTYSMB_BMC_MM7_R_SDACHIPCHIPCHIPCHIPCHIPFM_BMC_EN_DET_RCHIP10121012SMB_BMC_MM16_SDACHIPSMB_BMC_MM15_SDASMB_BMC_ALERT15_N15SPI_BMC_BOOT_MISOSTRAP 0, ENABLE LOW SECURE BOOT FUNCTION0, JUST LEAVE THE PIN FLOATING OR PULL DOWN(DEFAULT)1, PULL-HIGH THE PIN BY A RESISTOR OF VALUE 1K ~ 4.7K OHM1, ENABLE SCURE BOOT ,PULL-HIGH THE PINSPI_BMC_BOOT_MOSI1, PULL-HIGH THE PIN BY A RESISTOR OF VALUE 1K ~ 4.7K OHMSPI_BMC_TPM_MOSISTRAP 6, SELECT LPC/ESPI0, ESPI (DEFAULT)13210, DISABLE SECURE BOOT,PULL DOWN(DEFAULT)STRAP 31, ENABLE SECURE BOOT BY PIN STRAP
1010CHIPSMB_BMC_MM2_SDA2.2K2.2K10UART_BMC_5_TXD_R10 35271300, JUST LEAVE THE PIN FLOATINGSTRAP 8, ENABLE BOOT FROM UART54.7KEMPTYEMPTYFM_BMC_DISABLEEMPTY2N7002A-7BAM700200684613LPC_ESPI_SELCHIPCS24702FB060402LFLPC_ESPI_SEL_R1Q7_D1321EMPTY1/16WEMPTYSMB_BMC_ALERT16_N12121/16WCHIP0402LF1%4.7K1/16WEMPTY0402LF1%4.7K0402LF1%4.7K1001%3512151312101117
10 1212 10121212121210101327 3030481313 211212 1012101212 1010 121210 1210 1212 10121012 1012261010 12264.7KCHIPCHIPEMPTY4.7KSMB_BMC_MM16_SCL4.7K4.7K4.7K0CS11002FB070402LF1/16W0402LFEMPTY1, LPCTMP_QCH5103K9B001UFSMLFIC1/16W2K1%CHIP16V040210%1%4.7K
2.2K2.2K2.2K2.2KSMB_BMC_MM14_SDACHIPSMB_BMC_MM14_SCLCHIPSMB_BMC_MM13_SDACHIPSMB_BMC_MM13_SCLCHIP2.2K0
4.7K4.7K4.7K4.7K4.7K4.7K4.7KBIOS IS HIGH ACTIVITYIF BMC DISABLE,TO PCH GPIO AND BIOS CONTROL,UART_BMC_5_TXD_RBAT54CSMLFICBCBAT54CZ04FM_BMC_ONCTL_R_N4.7K1%1/16WCHIP0402LFSPI_BMC_BOOT_CLK2.2KCHIP26 3515CHIPCHIPCHIPSMB_BMC_MM15_SCLSMB_BMC_MM12_SDASMB_BMC_MM12_SCLCHIP2.2K2.2KCHIPCHIP10K10K10KCHIP49910KSMB_BMC_MM6_SDA2.2KCHIP10K10KCHIP10KCHIPCHIP
R251
R250
R94 R164 S
G
D
R438
R429
R428
R422
R692
R610
R149
R145
R521
R753R140
R770
R754 R430
U11
R851
R848
R846
R844
R843
R842
C267
R714
R699
R244
R245
R246
R247
R249
R248
R252
R253
R255
R254
R256
R257
R258
R260
R259
R266
R261
R262
R264
R265
R268
R267
R269
312
Q7
S
D
G
CAB
21
2
1
21
21
21
21
21
21
21
21
21
2
1
R42
DESIGN NOTE:
DESIGN NOTE:
DESIGN NOTE:
DESIGN NOTE:
DESIGN NOTE:
DESIGN NOTE:
2
1
2
1
2
1
2
1
SHEETDATE
DEPARTMENT
SIZE
PROJECT DOCUMENT NUMBER REV
REVIEWER
DESIGNER
123
7 3 2 1 6 5 4
E
A
B
C
E
D
C
B
A
7 6 5 4
D
OUT
OUT
OUT
OUT
OUT
OUT
OUT
OUT
OUT
OUT
OUT
OUT
OUT
OUT
OUT
OUT
OUT
IN
OUT
OUT
OUT
OUT
OUT
OUT
OUT
OUT
OUT
IN
OUT
OUT
OUT
OUT
OUT
OUT
OUT
OUT
OUT
OUT
OUT
OUT
OUT
OUT
OUT
OUT
OUT
OUT
OUT
OUT
OUT
C



NOTE:PU ON BMC SIDE
PCA9555 ADDRESS: 0X4E [0 1 0 0 A2 A1 A0 0]CAD NOTE: PLACE AS CLOSE AS POSSIBLE TO TPS2553Fri Aug 25 17:25:41 2023<NAME_2><NAME_1>NANANA28 OF 60USB - DEBUG CONNECTOR 1/2
P5V_AUXP5V_USB_REARP3V3_AUXP3V3_AUXP3V3_AUX
P3V3_AUXGNDGNDGND
P3V3_AUXP3V3_AUXGNDP3V3_AUXP3V3_AUXGNDGNDP5V_AUXP3V3_AUXP3V3_AUXP3V3_AUXGND
GNDGNDP5V_AUXCHIPCS11002FB07USB_OC0_REAR_R_N100DEBUG_PORT_PRSNT_BUF_ENSMB_DEBUG_AUX_LVC3_USB_R1_SDASMB_DEBUG_AUX_LVC3_USB_R1_SCLCHIP1/16W1%4.7K153528USB_OC0_REAR_NCHIP0CS00002JB130402LFCS32002FB06CHIP1/16WUSB_OC0_ILIM1%20KCS31002FB080402LF282828LED_POSTCODE_INTLED_POSTCODE_A0USB_OC0_EN25V10%X7RCH4104K1B00SMB_DEBUG_AUX_LVC3_USB_R3_SDASMB_DEBUG_AUX_LVC3_USB_R3_SCL5%SMB_DEBUG_AUX_LVC3_USB_SCLPWRGD_PSU_AC_PWROKFM_CPU_MSMI_CATERR_LVT3_NFM_SLPS3_GF_N1/16W 0402LFPWRGD_DSW_PWROKRST_PLTRST_NPWRGD_SYS_PWROKFM_UART_SEL_NFM_SOL_UART_CH_SEL_R3 FM_SOL_UART_CH_SEL3615100402LF1/16WCHIP5%01/16W1%1K0402X7R10%50V470PF33.233.2CS24702FB060402LFCS24702FB060402LF1/16W1%CHIP4.7KSMB_DEBUG_AUX_LVC3_USB_SCLSMB_DEBUG_AUX_LVC3_USB_SDACHIPCHIP292829CH4104K1B001%DEBUG_PORT_PRSNT29CS41002FB0910%CH4104K1B000402
47EMPTY1/16W1/16W1/16WCHIPCHIP5%CHIP0402LF0402LF0CHIP0402LF1011FM_UART_SWITCH_NFM_CPU_MSMI_CATERR_LVT3_R3_NCHIP1/16WBAM700200682N7002A-7CS21002FB061K25V0.1UFDEBUG_PORT_PRSNT_BUF_EN0402LFCS00002JB131%1/16W10KCHIP28282810 11 1322 3436 421311 1234 462829 133511341310 1335472850504747474747472829
12271227282828100KIC74LVC1G07W5-7SMLF05%CHIPICAL009517K001%EMPTYCS24702FB061%IC040222UF10V20%X6S0402LFCS11002FB070402LFPCA9555PW1/16W0402LFCHIP10%4.7K1%1/16W10KCHIP1% 1%4.7K1%4.7KCS21002FB060402LFCHIP0402LFCHIP1/16W1%0402LFCHIP 1/16W5%00402LF1%1001/16W1005%05%00402LF1/16W1%EMPTY1000402LF CHIP1/16W0SMB_DEBUG_AUX_LVC3_USB_SDA0402LF 1/16W0402LF1/16W5%00402LF5%0PWRGD_SYS_PWROK_R15%0
01/16W
0402LED_POSTCODE_A1LED_POSTCODE_A2ICSMLF0.1UFSMLFICLED_POSTCODE_0_R1FM_UART_SWITCH_NFM_DEBUG_PWR_BTN_NFM_DEBUG_RST_BTN_NLED_POSTCODE_7_R1
X7R25V
LED_POSTCODE_1_R1
0402LFSMLFPCA9517ADP10KCHIP1/16W1%25V0.1UF10%
LED_POSTCODE_2_R1LED_POSTCODE_3_R1LED_POSTCODE_4_R1LED_POSTCODE_5_R1LED_POSTCODE_6_R1FM_SLPS3_GF_R2_NPWRGD_DSW_PWROK_R3RST_PLTRST_R2_N0CHIPCS24702FB06
0.1UFX7R1/16W1/16WCHIP1/16WEMPTY EMPTY0402LFCHIP0402LF1/16W1/16W4.7KCS24702FB065%0402LFCHIP1%
1/16WEMPTYALVC1G070010402CH4104K1B00X7RSMB_BMC_MM15_SCLSMB_BMC_MM15_SDALED_POSTCODE_A0LED_POSTCODE_A1LED_POSTCODE_A2TMP_QAL009555K044.7KC0805CH6222MEA00CS31002FB080402LFAL000380K00NCP380HSNAJAAT1GSMLFSMB_BMC_MM15_R1_SDASMB_BMC_MM15_R1_SCLCHIPDEBUG_PORT_PRSNT_BUF_R_EN0402LFCS31002FB08
R384
R302
R300
4
51
3
2
61
5 2
43
R743 R744 R745
R738 R739 R740
R83
S
G
D
R626
R632
R95
C300
R721
R720
12
24
23
22
20
19
18
17
16
15
14
13
11
10
9
8
7
6
5
4
1
3
2
21
R719
R703
R702
R701
R295
R135
R294
R670
81
63
72
4 5
R377
R376
R378
R383
C171 C172
U23
U10
Q8
U40
U37
SCLA
ENABLE
VCCA VCCB
SDAA SDAB
SCLB
GND
NC1
YGND
A
VCC
GND
EN
OUT
ILIM
IN
FLAG_N
S
D
GVDD
VSS
I\N\T\
SDA
SCL
P00
P01
P02
P03
P04
P05
P06
P07
P10
P11
P12
P13
P14
P15
P16
P17
A0
A1
A2
21
21
21
2
1
2
1
2
1
2
1
2
1
2
1
2
1
2
1
2
1
2
1
2
1
2
1
2
1
2
1
2
1
21
21
2
1
2
1
SHEETDATE
DEPARTMENT
SIZE
PROJECT DOCUMENT NUMBER REV
REVIEWER
DESIGNER
123
7 3 2 1 6 5 4
E
A
B
C
E
D
C
B
A
7 6 5 4
D
IN
BI
IN
OUT
OUTOUTOUT
IN
OUT
BI
IN
INININ
IN
IN
OUT
OUTOUT
ININ
IN
ININ
ININ
IN
IN
INININ
IN
BI
OUT
OUT
C157
R735
R736
R667
R296
C158
C159
R298 R299
C



CAD NOTE: PLACE AS CLOSE AS POSSIBLE TO USB CONNECTORFri Aug 25 17:25:42 2023<NAME_2><NAME_1>NANANA29 OF 60USB - DEBUG CONNECTOR 2/2
P5V_USB_REARGNDP3V3_AUXP5V_USB_REARGNDGNDGND
GNDP3V3_AUXP5V_USB_REARGNDP3V3_AUXGND
P3V3_AUXP3V3_AUXP3V3_AUXP3V3_AUXGNDGNDGNDGNDGNDGND
GNDGNDDEBUG_PORT_PRSNT33.229DEBUG_PORT_PRSNT_RUSB3_01_FB_RXNCHIPUSB3_01_FB_RXPUSB2_01_F_DNUSB2_01_F_DP2928USB3_FPNL_TXPUSB3_FPNL_TXN2910CS32002FB061/16WCHIP0402LFFM_DEBUG_PORT_R_PRSNT_NFM_DEBUG_PORT_PRSNT_N13360402LFCS24702FB06USB3_01_FB_TXPUSB3_01_FB_TXN4.7K1%1/16WCHIPSMLF2N7002A-7BAM70020068DFHS09FR401CONN9_GSB3111315HRIOTHLF47UF50V10%04021/16W0402LF67/320MACX21SN67000CS00002JB13470PF50VCHIP1/16WBC001240Z01CS00002JB130402LF5%01/16W74HC1G126GWDEBUG_PORT_UART_RXCH4104K1B00040274HC1G126GWSMLF0CHIPDEBUG_PORT_UART_RXSMB_DEBUG_AUX_LVC3_USB_R2_SCLSMB_DEBUG_AUX_LVC3_USB_R2_SDADEBUG_PORT_UART_TXSMB_DEBUG_AUX_LVC3_USB_SDASMB_DEBUG_AUX_LVC3_USB_SCL00402LF1/16W5%CHIP1/16W0CHIP 0402LF5%0402LF0402LFCS31002FB0828 29291/16W10K1%EMPTYUSB3_MUX_PDCS11002FB07DEBUG_PORT_PRSNTUSB3_01_MUX_FB_RXNUSB3_01_MUX_FB_RXPUSB3_01_MUX_FB_TXNUSB3_01_MUX_FB_TXP0402CH4104K1B000.1UF0402LFUSB2_01_F_DPUSB2_01_F_DN320MASMLFCHIP5%CHIPCS00002JB13CX21SN670000402LFCS00002JB13CHIP5%29 28
29293129292929
2928292929 2929 28
292928282929
29292931102929292910 101010CH6471ME200C1206X6S20%6.3VX6SCH6471ME20020%C12066.3V47UFCS00002JB135%1/16WPI3PCIE3212ZBEXCS00002JB13
USB3_01_MUX_FB_RXPUSB3_01_MUX_FB_RXNSPA_SOUT_SW_DBGICAL1G01260071/16W1%EMPTYCS41002FB090402LF1/16W0.1UF10%CH4104K1B000402SMLFAL003212003USB3_01_TXN_C0402LFCHIPEMPTY25V 0.1UFCH4104K1B0010%0CS00002JB130402LF320MA1/16WCH4104K1B00DEBUG_PORT_PRSNTAL1G0126007SMLFSMLF320MAUSB3_01_FB_RXN1/16WCS00002JB13USB3_01_FB_TXPUSB3_01_FB_RXP0SMLFICCX21SN67000SMLF25VIC25VDEBUG_PORT_UART_TXDEBUG_PORT_PRSNT470PFIC
X7RX7RX7RX7R10%10%10%0.1UF0.1UF04020402EMPTY05% EMPTY1%100KCS41002FB090402LFCS41002FB091%1/16WCHIP0402LF100K20K1%CHIP1%10025V0402X7RCH4104K1B0025VX7R1/16WIC DEBUG_PORT_PRSNT0402LF 1/16W5%10%25V0.1UFX7R
100K67/320MAUSB3_01_MUX_FB_TXPUSB3_01_MUX_FB_TXN05%CHIP67/320MAEMPTYSPA_SIN_SW_DBGAL5V0U2X000PRTR5V0U2XCHIP5%0EMPTY1/16W0USB_FPNL_DN0402LFICUSB3_01_FB_TXN1/16WSMLFDT1240E-04LP-7
05%CHIP10%USB_FPNL_DP25VCS00002JB130402LFUSB3_FPNL_RXNUSB3_FPNL_RXP040210%USB3_01_TXP_CCH4104K1B000.1UFEMPTY0402
3 state output
3 state output
C327C177
R693
1
8
9
5
6
7
4
G2
G1
2
3
8
3
10
9
7
6
5
4
2
1
10
6
1
TH
9
2
11
5
20
13
12
15
14
17
16
19
18
7
8
3
4
S
G
D
R707
C178 C179
3
5
42
3
5
4 2
R672
C239
C238
R671
R732
R731
R666
43
2 1
L21
R673
43
2 1
L22
R668
R675
4 3
21
L23
R386 4
3
2
1
U38
R385
11
J2
U27
U22
Q6
U29
U36
IO2
VCC
GND
IO1
Standard-A
SSRX-
GND_D
SSRX+
D+
D-
SSTX-
SSTX+
G2
G1
GND
VBUS
NC2
IO4
IO2
NC4
NC3
VSS2
NC1
IO3
VSS1IO1
PD
GND0
GND1
GND2TH
C1_N
C1_P
C0_N
C0_P
B1_N
B1_P
B0_N
B0_P
SEL
A1_N
A1_P
A0_N
A0_P
VDD0
VDD1
VDD2
S
D
G
GND
5
42
GND
5
4 2
12
3 4
12
3 4
1 2
34
11
21
2
1
2
1
2
1
2
1
2
1
2
1
2
1
2
1
2
1
2
1
2
1
2
1
2
1
2
1
2
1
2
1
21
21
SHEETDATE
DEPARTMENT
SIZE
PROJECT DOCUMENT NUMBER REV
REVIEWER
DESIGNER
123
7 3 2 1 6 5 4
E
A
B
C
E
D
C
B
A
7 6 5 4
D
BI
BI
OUTOUT
ININOUTOUT
IN
OUT
OUT
BI
BIIN
OUT
OUT
IN
IN
IN
OUT
OUT
IN
IN
IN
IN
IN
OUTIN
INBI
OUT
OUT
IN
IN
IN
IN OUT
OUT
BI
BI
R730
R205
C148
R219
R193
C149
R274
R694
R712
C219 C236 C237
C



ISOLATION FOR BMC TXD5/RXD5BMC SIDEBMC SIDEISOLATIONOPEN-DRAINRESERVED DEBUG HEADERUART SWITCHBMC SIDEAND BMC_DEBUGMUX FOR SWITCHING SYSTEM (BIOS)
DEBUG HEADER SIDEUART SWITCHOPEN-DRAINBMC SIDEDEBUG HEADER SIDE
S2CONNECTOR SIDEFUNCTION
RESERVED DEBUG MINI-USBISOLATIONCONNECTOR SIDES1BMC AND TXD5/RXD5 ISOLATION BUFFERDEBUG HEADER SIDEBMC AND TXD5/RXD5 ISOLATION BUFFERHIGHHIGHHIGHLOWLOWB2 CONNECTED TO AB0 CONNECTED TO AB1 CONNECTED TO AHIGH
Fri Aug 25 17:25:42 2023<NAME_2><NAME_1>NANANA30 OF 60BMC DEBUG PORT 1/2
P3V3_AUXP3V3_AUXP3V3_AUXP3V3_AUXP3V3_AUX
P3V3_AUX
P3V3_AUX
P3V3_AUXP3V3_AUXP3V3_RGMP3V3_AUXUART_BMC_5_RXD_BUF14.7KICCH4104K1B0004024.7KUART_BMC_5_RXD_RUART_BMC_5_TXD_BUF1_R1%1/16WCS24702FB06CS24702FB060402LF30UART_BMC_5_TXD_BUF_REMPTYUART_BMC_5_TXD_RSMLF
SMLFUART_BMC_5_TXD_BUF1_RFM_UARTSW_MSB_NFM_UARTSW_LSB_NSPA_SIN_SW_BUFUART_BMC_1_TXD_RUART_BIC_DBG_TXAL0033570090402X7RCHIPCS24702FB06SPA_SOUT_SW_BUFCH4104K1B00
3030UART_BMC_5_RXD_BUF1_RUART_BMC_5_TXD_BUF125V0.1UF1%1/16W25VUART_BMC_5_RXD_BUF_R1/16W33.20402LFCHIP30UART_BMC_5_RXD_BUFUART_BMC_5_TXD_BUF1_R UART_BMC_5_TXD_BUFUART_BMC_5_RXD_BUF130UART_BMC_5_TXD_BUF_R1%0402LFSPA_SIN_SW_BUF_RCHIPCS00002JB1300402LFUART_BMC_5_RXD_BUF1UART_BIC_DBG_RXUART_BMC_5_RXD_BUF1_SW36304949313013FSA3357K8XAL003357009CH4104K1B00301%1/16W27SMLFCS00002JB1310%25VFSA3357K8XX7RUART_BMC_1_RXD_R004024.7K1/16WX7R0.1UF10%0402IC
1/16WAL002G07003UART_BMC_5_RXD_BUFIC1/16W10%0.1UFX7R1%33.21%
1%4.7K1%SMLF1%4.7K4.7K0402LF0402LF0.1UF25VIC0402LF 1/16WCHIP33.2CHIPSMLF74LVC2G07DW-7CH4104K1B0010%CHIP1/16WCHIPCHIP33.20402LF33.20402LF1%0402LFCS24702FB06CHIP1/16WCHIPCHIP1/16W1%0402LF0402LFCS24702FB061%4.7KCS24702FB060402LFCS24702FB061/16WFM_UARTSW_LSB_NFM_UARTSW_MSB_N74LVC2G07DW-7AL002G07003
EMPTYEMPTYCHIPSPA_SOUT_SW_BUF_R49 3649 30 36311330 303030 36
30133131SCONN3_212-91-035BR2DFHD03MS251130402LF
R39
R726
C19
C20
8
5
6
4
3
2
1
7
8
5
6
4
3
2
1
7
52
43
61
52
43
61
R765
R766R72 C268
R757
R715
R758
R741
R742
R737
3
2
1
C175
R102
R104
R67
U3
U2
U47
U24
J6
S1
B0
B1
VCC
S2
B2
GND
A
S1
B0
B1
VCC
S2
B2
GND
A
VCCGND
2Y
1Y
2A
1A
VCCGND
2Y
1Y
2A
1A1
2
3
DESIGN NOTE:
21
21
2
1
2
1
2
1
21
2
1
2
1
21
21
2
1
2
1
2
1
2
1
2
1
21
21
2
1
SHEETDATE
DEPARTMENT
SIZE
PROJECT DOCUMENT NUMBER REV
REVIEWER
DESIGNER
123
7 3 2 1 6 5 4
E
A
B
C
E
D
C
B
A
7 6 5 4
D
OUT
ININ
ININ IN
IN
IN
OUT
OUT
IN
OUT
OUT
IN
IN
IN
OUT
OUT
OUT
OUT
ININ
C



NOTE: RESERVED SWITCH UART TO SYS,B1(DEFAULT)R628 CHANGE FROM 0 TO 100_20230314NOTE: RESERVED SWITCH UART TO SYS,B1(DEFAULT)NOTE: BIC SWITCH UART,B0 IS BMC,B1 IS DEBUG CARDADD PU_20220804NOTE: BIC SWITCH UART,B0 IS BMC,B1 IS DEBUG CARDADD DBG CARD OR SYS DEBUD SELECTION
Fri Aug 25 17:25:43 2023<NAME_2><NAME_1>NANANA31 OF 60BMC DEBUG PORT 2/2
I24
I38
I23I27P3V3_AUXP3V3_AUXP3V3_AUXP3V3_AUXP3V3_AUXP3V3_AUXP3V3_AUXICALSB3157000CS00002JB13CS11002FB071%1005%00402LF0402LFCHIPSPA_SIN_SW_DBG_RUART_SYS_DBG_RX_RUART_SYS_DBG_RXNC7SB3157P6X0.1UFBMC_CPLD_GPIO_2CHIPNC7SB3157P6X0.1UF10%X7RCH4104K1B000402ALSB315700042 34130402LF0402LFPU_J13_P1EMPTYDFHD03MS161SCONN3_212-H91-03GBR1SMLF31UART_BIC_DBG_TX0402CS41002FB09UART_BIC_GF_RXDFM_BIC_DEBUG_SW_NNC7SB3157P6XNC7SB3157P6XALSB31570004.7K1%1/16WCS24702FB06CS00002JB13SPA_SOUT_SW_BUF_R3110100K1/16WCHIP0402LF1%10FM_BIC_DEBUG_SW_NUART_BIC_GF_TXDUART_6_BMC_TXD_RSPA_SOUT_SW_DBGUART_SYS_DBG_TX0402LF0402LFCHIP5%CHIP300FM_DBG_SW_N31SPA_SIN_SW_DBG
UART_BIC_DBG_RX_RUART_BIC_DBG_RXUART_6_BMC_TXD0CHIP0CHIPUART_6_BMC_RXDUART_BIC_DBG_TX_RUART_6_BMC_RXD_R0CHIP0CHIP
NC7SB3157P6XICNC7SB3157P6X0.1UFCH4104K1B0025VFM_DBG_SW_NSPA_SIN_SW_BUF_R
10%2910291030
30
13 3130 13
311212
CH4104K1B0010%X7R0402
ICX7R0402ICCH4104K1B000.1UFX7R25V10%NC7SB3157P6XNC7SB3157P6XALSB31570000402LFCS41002FB091/16WCHIP1%100K25V25V05%CHIPFM_DBG_SW_N5%CS00002JB13CS00002JB130CHIPUART_SYS_DBG_TX_RSPA_SOUT_SW_DBG_R
R630
5
6
2
1
3 4
5
6
2
1
3 4
5
6
2
1
3 4
5
6
2
1
3 4
S
B0
B1
VCCGND
A
S
B0
B1
VCCGND
A
S
B0
B1
VCCGND
A
S
B0
B1
VCCGND
A
R396
R629
R628
R618
R546
R544
R903
R902
R901
R900
3
2
1
C231
C11
C500
C501
J13
U20
U7
U51
U50
1
2
3
2
1
2
1
21
21
21
21
21
21
21
21
21
2
1
2
1
2
1
R538
2
1
2
1
SHEETDATE
DEPARTMENT
SIZE
PROJECT DOCUMENT NUMBER REV
REVIEWER
DESIGNER
123
7 3 2 1 6 5 4
E
A
B
C
E
D
C
B
A
7 6 5 4
D
IN
IN
OUT
OUT
IN
OUT
IN
OUT
IN
OUT
OUT
IN
IN
IN
IN
IN OUT
IN
C



JTAG MASTER PU/PD RESISTOR
FOR FPGA PROGRAMMING
Fri Aug 25 17:25:43 2023<NAME_2><NAME_1>NANANA32 OF 60BMC - JTAGP3V3_AUX
P3V3_AUX
P3V3_RGM
0.1UFCH4104K1B000402JTAG_SCM_PLD_R1_JTAGENTP_PLD_CONN_P532JTAG_SCM_CONN_TDOTO DEBUG CONNTO SCM GF33.2 CHIPJTAG_MB_TDIJTAG_MB_TMSJTAG_MB_TDOJTAG_MB_TDIJTAG_MB_TMSJTAG_MB_TDOJTAG_MB_TRST_NJTAG_MB_TCKEMPTY10K10KCHIP3232153215JTAG_MB_TCKJTAG_MB_TRST_NCHIP33.2JTAG_SCM_CONN_TCKJTAG_SCM_CONN_TDOJTAG_SCM_CONN_TDIJTAG_SCM_PLD_JTAGENJTAG_SCM_CONN_TMS323232483234BC005819Z40TO FPGAFROM BMCJTAG_SCM_PLD_TCKJTAG_SCM_TCKJTAG_SCM_TMSJTAG_SCM_TDI33.2CHIP6.3V10%10UFIOCHIP
3210EMPTYEMPTY1510K10K15JTAG_1_BMC_TRST_RJTAG_1_BMC_TCK_RJTAG_1_BMC_TMS_RJTAG_1_BMC_TDI_RJTAG_1_BMC_TDO_RSMLFJTAG_SCM_PLD_TDO25VX7RC0402CH6101MEB01X6S20%IC1N5819HWJTAG_SCM_CONN_TMSCHIPJTAG_SCM_PLD_TDIFROM BMCJTAG_SCM_TDO0402LF1%1/16WCHIPCHIPCHIP33.233.2CHIPJTAG_SCM_CONN_TDI
JTAG_SCM_NTRST10KCHIPJTAG_SCM_TCK
4.7K CHIPJTAG_SCM_PLD_TMSJTAG_SCM_CONN_TCK
4.7K EMPTYJTAG_SCM_TMSJTAG_SCM_TDI10KCHIPCHIP33.2
10K
JTAG_SCM_TDO33.233.2CHIP33.2CHIPCHIP10K10KCHIP10KCHIP33.2CS03322FB0333.2CHIP33.2CHIP33.233.2CHIPJ7_P1THLFCONN8_210-HP1-080BR1DFHD08MS39234323432101032153215321532
15
34103210321032323234
321515153215151032103232
3215
2 1
R206
R285
R202
8
7
6
5
4
3
2
1
R834
R512
R513
R511
R510
R204
R523
R203
R228
R229
R230
R227
R226
R517
R515
R516
R514
R639
R224
R221
R222
R223
R518
C215 C217
D20
J7
C A
8
7
6
5
4
3
2
1
21
21
21
DESIGN NOTE:
DESIGN NOTE:DESIGN NOTE:
DESIGN NOTE: DESIGN NOTE:
21
21
21
21
21
21
21
21
21
21 21
21 21 21
SHEETDATE
DEPARTMENT
SIZE
PROJECT DOCUMENT NUMBER REV
REVIEWER
DESIGNER
123
7 3 2 1 6 5 4
E
A
B
C
E
D
C
B
A
7 6 5 4
D
OUT
OUT
OUTINININ
OUT
IN OUT OUT
OUTOUT
OUTINININ
OUT
OUT
IN
OUT
OUTOUTOUTINININ
OUT IN
OUT
OUT
OUT
OUT
IN
OUT
OUT
OUT
OUT
C



Fri Aug 25 17:25:43 2023<NAME_2><NAME_1>NANANA33 OF 60BLANK PAGE
SHEETDATE
DEPARTMENT
SIZE
PROJECT DOCUMENT NUMBER REV
REVIEWER
DESIGNER
123
7 3 2 1 6 5 4
E
A
B
C
E
D
C
B
A
7 6 5 4
D
C



FOR CPLDFri Aug 25 17:25:43 2023<NAME_2><NAME_1>NANANA34 OF 60FPGA 1/8P3V3_AUXPVCCIO_AUX_PLDP3V3_AUXPVCCIO_AUX_PLDVCCIO0P3V3_AUXVCCIO2VCCIO0
P3V3_AUX211546 281213 1134320.1UFCH4104K1B0010K33.225MHZSMLFIRQ_OC_DETECT_EN_NFM_ADR_COMPLETEIRQ_OC_DETECT_NTP_PLD_19D22IRQ_PCH_SCI_WHEA_NAJ021000T03463621124636211213283113274.7K
FM_TPM_PRSNT_0_NH_CPU1_PROCHOT_LVC1_R_N341313121313151515 3415151515
343634 1234111010111110111015152232 48111328153413421215131542102210111315
CH5104KEB02IRQ_BMC_PCH_NMI_NFM_PCH_BMC_THERMTRIP_NIC
BF6250000231%0402CHIP1%CS03322FB03CS00002JB1310KPU_FPGA_NSTATUSPU_FPGA_NCONFIGPU_FPGA_CONFIG_DONE1/16W0C0402X6S25V1UF10%CHIPCHIP10KCHIPX7R10%040225V
4.7K1%CHIP
MISC1/16W 0402LFX7R0.1UF25V10%1/16WCHIP0402LFPU_25M_FPGA_CLK_ENCLK_25M_OSC_FPGARST_RSMRST_NIRQ_CPU0_VRHOT_NIRQ_CPU1_VRHOT_NPWRGD_CPUPWRGD_LVC1150402LF5%CHIP1311IRQ_UV_DETECT_NRST_BMC_RSTBTN_OUT_NBMC_CPLD_GPIO_2FM_ME_BT_DONEFM_PCIE_M2_SSD0_PRSNT_NPU_PT20DRST_SRST_PLD_BMC_R_NFM_BIOS_POST_CMPLT_BMC_N464615PWRGD_PCH_PWROKSMLFLCMXO3LF-2100C-5BG256C
CLK_25M_OSC_FPGA
FM_TPM_PRSNT_0_R_NCHIPCHIPFM_TPM_PRSNT_1_N FM_TPM_PRSNT_1_R_NIRQ_BMC_CPU_NMI_RFM_JTAG_BMC_MUX_SELJTAG_SCM_PLD_TDI32RST_RSMRST_NJTAG_SCM_PLD_TDORST_PLTRST_NPWRGD_PSU_AC_PWROKRST_PCA9548_SENSOR_NBSM_PRSNT_R_NFM_BMC_DBP_PRESENT_N3233.23233.233.233.2PU_FPGA_CONFIG_DONE34CHIP33.2SGPIO_CLK_PLD_0 SGPIO_CLK_033.2 CHIPSGPIO_PLD_DO_0 SGPIO_DO_033.2 CHIPSGPIO_PLD_LD_0 SGPIO_LD_033.2 CHIPSGPIO_DI_0PU_FPGA_NSTATUS33.2 CHIPRST_SRST_PLD_BMC_R2_N0CHIPSMB_BMC_MM16_R5_SCL0SMB_BMC_MM16_R5_SDASMB_BMC_MM16_R3_SDASMB_BMC_MM16_R3_SCL00JTAG_SCM_PLD_JTAGENCHIP0RST_EXTRST_NRST_EXTRST_R_NCHIPFM_CPU_MSMI_CATERR_LVT3_N10KCHIPCHIPCHIPCS31002FB08SGPIO_PLD_DI_0FM_THERMTRIP_DLY_LVC1_R_NJTAG_SCM_PLD_TCKJTAG_SCM_PLD_TMSIRQ_BMC_PCH_NMI_R_N0CHIP0BMC_CPLD_GPIO_2_R2CHIPPWRGD_PSU_AC_PWROK_PLDRST_PLTRST_R1_NCHIPCHIP33.2CHIP0CHIPBSM_PRSNT_R1_NFM_JTAG_BMC_MUX_SEL_R2JTAG_SCM_PLD_R_JTAGENFM_CPU_MSMI_CATERR_LVT3_PLD_N
CLK_25M_OSC_FPGA_R
R447
R397
R303
R272
R270
R437
R436
R435
R434
R459
R837
R718
R123
R10
R767
R519
R297
OSC2
R807
C318
R806
R808
R810
R809
R634
R571
R625
G9
G8
D12
D5
C13
A13
A15
B14
B12
C12
A14
B13
A12
B11
D11
F10
C11
A11
B10
C10
E10
D10
E11
F9
A10
B9
C9
A9
D9
F8
E9
D8
A8
C8
B8
A7
E8
F7
D7
E6
C7
B7
A6
C6
E7
D6
B4
A3
B6
A5
C5
A4
B3
B5
C4
U25
VDD OUT
GNDOE
1/7
BANK0 PT18A
PT24D||DONE
PT24C||INITN
PT24B
PT24A
PT23B
PT23A
PT22D
PT22C
PT22B
PT22A
PT21D
PT21C
PT21B
PT21A
PT20D||PROGRAMN
PT20C||JTAGENB
PT20B
PT20A
PT19D
PT19C
PT19B
PT19A
PT18D||SDA||PCLKC0_0
PT18C||SCL||PCLKT0_0
PT18B
PT17D
PT17C
PT17B||PCLKC0_1
PT17A||PCLKT0_1
PT16D||TMS
PT16C||TCK
PT16B
PT16A
PT13D
PT13C
PT13B
PT13A
PT12D||TDI
PT12C||TDO
PT12B
PT12A
PT11D
PT11C
PT11B
PT11A
PT10B
PT10A
PT9C
PT9B
PT9A
VCCIO0_G9
VCCIO0_G8
VCCIO0_D12
VCCIO0_D5
21
21
21 21
21
21
21 21
21
21
21 21
21
21
2
1
2
1
21
21
2121
4 3
1 2
21
2
1
2
1
21
21 21
2
1
SHEETDATE
DEPARTMENT
SIZE
PROJECT DOCUMENT NUMBER REV
REVIEWER
DESIGNER
123
7 3 2 1 6 5 4
E
A
B
C
E
D
C
B
A
7 6 5 4
D
OUT
IN
OUT
OUT
OUTOUT
OUTOUT
OUTOUT
INOUT
OUT
OUT
OUT
INOUT
OUTIN
ININ
OUT
IN
ININ
INOUT
OUT
OUT
OUT
IN
IN
ININ
OUTBI
IN
IN
IN
OUT
OUT
OUTOUTOUT
IN
OUT
IN
INBI
IN
C257C256
R183
C



ADD_20221206
Fri Aug 25 17:25:44 2023<NAME_2><NAME_1>NANANA35 OF 60FPGA 2/8VCCIO1P3V3_AUXVCCIO1P3V3_AUXSDMK0340L-7-FCHIPCHIPFM_BMC_READY_PLD_NFM_BIOS_DEBUG_EN_N0EMPTYBC000340033RST_BMC_HW_RFM_SLPS3_GF_N28 PWR_LEDPWRGD_P5V_AUXPWRGD_P2V5_AUXCHIP0CHIPCHIP27 13221322 13SMB_BMC_ALERT10_N1113 FM_PWR_R_BTN5249155552511313152715282813111056H_CPU1_MEMTRIP_LVC1_NFM_SPD_REMOTE_EN_RH_CPU0_MEMTRIP_LVC1_NFM_BMC_ONCTL_R_NFM_PCHHOT_R_NTP_PLD_L3SMB_BMC_ALERT4_NSMB_BMC_ALERT3_NSMB_BMC_ALERT9_N2715271327131327132715VOL_SEN_ALERT_RFM_PECI_SEL_N15 424211 13 101510 11 131515131036 4242152610131513SMLFICLCMXO3LF-2100C-5BG256CAJ021000T03
EMPTY4.7K272711131542CHIP33.233.2 CHIPCHIPFM_ESPI_PLD_EN33.2FM_THROTTLE_NFM_PMBUS_ALERT_ENPWRGD_SYS_PWROK_PLD33.2 CHIP33.233.2BMC_CPLD_GPIO_8BMC_CPLD_GPIO_733.2 CHIPRST_SGPIO_RESET_N33.2 CHIPIRQ_SGPIO_NIRQ_SGPIO_R_NRST_SGPIO_RESET_R_NBMC_CPLD_GPIO_7_R20AC_PWR_BTN_R2_NH_CPU0_PROCHOT_LVC1_NRST_MB_STBY_NFM_ADR_TRIGGER_NFM_BMC_EN_DET_R0000CHIPCHIPCHIPCHIPCHIPCHIP33.20CHIPBMC_CPLD_GPIO_12_R2BMC_CPLD_GPIO_13_R233.20FM_PWR_BTN15RST_BMC_HWBMC_CPLD_GPIO_12BMC_CPLD_GPIO_13AC_PWR_BTN_R1_N33.2RST_ROT_CPU_N0 33.2 EMPTYEMPTY33.2BMC_CPLD_GPIO_8_R2CHIPCHIPPWRGD_P3V3_AUXPWRGD_SYS_PWROK545353CHIPAC_PWR_BTN_R1_NSMB_BMC_ALERT16_R2_NEMPTYRST_MB_STBY_R_NH_CPU0_PROCHOT_LVC1_R_NFM_THROTTLE_R_NFM_ESPI_PLD_R_ENSMB_BMC_ALERT3_R1_NSMB_BMC_ALERT4_R1_NSMB_BMC_ALERT9_R1_NSMB_BMC_ALERT10_R1_N0CHIPFM_SLPS3_GF_R_NRST_ROT_CPU_R_N42RST_BMC_SELF_HW_R2RST_BMC_SELF_HW15SMB_BMC_ALERT16_N22USB_OC0_REAR_R_NSMB_BMC_ALERT12_N0PWRGD_P2V5_AUX_R1PWRGD_P3V3_AUX_R1PWRGD_P5V_AUX_R1PWR_LED_CPLDCHIP4.7KPWRGD_P5V_AUX_R1
R886
2 1
R690
R691
R526
R531
R537
R536
R638
R841
R263
R769
R833
R825
R773
R472
R463
R432
R317
R318
R320
R271
R51
R574
R457
R456
R454
R453
M13
J10
H10
E13
R16
P15
N14
N16
P16
N15
M15
M14
L13
K11
M16
L15
K12
K13
L14
L16
L12
J11
K15
K14
J13
H11
K16
J15
J14
J16
H16
H14
J12
H13
H15
G16
H12
G11
G14
G15
G13
F12
F16
F14
G12
F13
F15
E16
D15
C16
E14
D16
B16
C15
E15
D14
D23
U25
12
2/7
DQ0
DQ1
BANK1
VCCIO1_H10
VCCIO1_E13 VCCIO1_J10
VCCIO1_M13
PR5B
PR5A
PR9D
PR9C
PR7D
PR7C
PR6D
PR6C
PR4B
PR4A
PR5D
PR5C
PR3B
PR3A
PR4D
PR4C
PR3D
PR3C
PR2D
PR2C
PR2B
PR2A
PR1D
PR1C
PR1B
PR1A
PR9B
PR9A
PR10B
PR10A
PR11B
PR11A
PR11D
PR11C
PR12B
PR12A
PR13B
PR13A
PR14D
PR14C
PR14B
PR14A
PR13D
PR13C
PR7B||PCLKC1_0
PR7A||PCLKT1_0
PR12D
PR12C
PR6B
PR6A
PR10D
PR10C
21
21
21 21
21
21 21
21
21
21
21 21
21 21
21
21
21
21
21 21
21
21
21
SHEETDATE
DEPARTMENT
SIZE
PROJECT DOCUMENT NUMBER REV
REVIEWER
DESIGNER
123
7 3 2 1 6 5 4
E
A
B
C
E
D
C
B
A
7 6 5 4
D
BI
OUT
OUT
IN
BI
IN
IN
OUT
OUT
OUTOUT
OUT
OUT
OUTIN
OUT
BIBI
BI
INBI
OUT
OUT
INOUT
OUT
IN
INOUTIN
OUT
OUT
OUT
BIIN
IN
ININ
OUT
IN
BI
IN
IN
BI
C



Fri Aug 25 17:25:44 2023<NAME_2><NAME_1>NANANA36 OF 60FPGA 3/8
VCCIO2VCCIO2VCCIO2CHIPCHIPCHIPCHIPCHIPCHIP12CHIP0CHIPRST_WDTRST_PLD_R2_NTP_PLD_C13FM_DEBUG_PORT_R2_PRSNT_NCHIP100000033.233.2NC_FM_PFR_UPDATE_NRST_PFR_OVR_RTC_RFM_JTAG_TCK_MUX_BMC_SEL0402LFCHIPCHIPCHIPCHIPCHIPRST_ROT_CPU_N0000000CHIP0402LFCHIPPU_FPGA_NCONFIGFM_UARTSW_LSB_NCHIPCHIPCHIPCHIPPWRGD_P1V8_AUXPWRGD_P3V3_RGMPWRGD_P1V2_AUX0000PWRGD_P1V8_AUX_R1PWRGD_P3V3_RGM_R1PWRGD_P1V0_AUX_R134FM_BMC_CPU_FBRK_OUT_R_NFM_BMC_DEBUG_SW_R2_NFM_BMC_DEBUG_SW_N33.2FM_BMC_CRASHLOG_TRIG_NIRQ_PCH_TPM_SPI_NFM_BMC_SUSACK_R2_NFM_BMC_SUSACK_NRST_WDTRST_PLD_NFM_SOL_UART_CH_SEL_R2FM_P12V_HSC_ENABLE_R2PWRGD_DSW_PWROK_R2FM_BMC_CRASHLOG_TRIG_R2_NNC_FM_PFR_NO_SERVICE_ACT_NGPU_NVS_PWR_BRAKE_R_NGPU_FPGA_RST_NCLK_BUF1_GPU_FPGA_OE_R_N13FM_BMC_UARTSW_MSB_N10SMB_BMC_MM16_R4_SCLSMB_BMC_MM16_R4_SDAFM_BMC_UARTSW_LSB_NCLK_GEN2_BMC_RC_OE_NIRQ_SML0_ALERT_R_NBMC_MONITER13FM_PCH_BEEP_LEDFM_HDD_LED_NFM_PFR_DSW_PWROK_NGPU_WP_HW_CTRL_R_N1%1/16WCHIP10KFM_UARTSW_MSB_R_NFM_UARTSW_LSB_R_NIRQ_PCH_TPM_SPI_R2_NFM_DEBUG_PORT_PRSNT_NPWRGD_DSW_PWROKFM_SOL_UART_CH_SELFM_P12V_HSC_ENABLESMB_BMC_MM16_R5_SDASMB_BMC_MM16_R5_SCL151315151513PU_PB25ALCMXO3LF-2100C-5BG256CAJ021000T03ICSMLFPWRGD_P1V0_AUXPWRGD_P1V2_AUX_R12813421329134813154613481313 46342112463421124930493022565655555452555254421315 1028421513 1113 1035CS31002FB08FM_UARTSW_MSB_N1012
R750
R445
R635
R748
R105
R114
R288
R134
R220
R899
R898
R379
R322
R323
R321
R746
R747
R578
R579
R577
R575
N12
N5
K9
K8
R14
T15
P13
R12
T13
P12
T14
R13
T12
R11
N11
M10
P11
T11
M11
N10
R10
P10
L10
M9
T10
R9
N9
M8
P9
T9
L9
N8
T8
P8
L8
M6
R8
T7
N7
M7
P7
R7
L7
N6
T6
P6
R4
T3
R6
T5
P5
R5
R3
T2
T4
P4
U25
3/7
BANK2
VCCIO2_N5
VCCIO2_N12VCCIO2_K9
VCCIO2_K8
PB9B
PB9A
PB8B||SO||SPISO
PB8A||MCLK||CCLK
PB8D
PB8C
PB6B
PB6A
PB6D
PB6C
PB5B
PB5A||CSSPIN
PB3D
PB3C
PB3B
PB3A
PB25D
PB25C
PB25B||SI||SISPI
PB25A||SN
PB24B
PB24A
PB22B
PB22A
PB22D
PB22C
PB21D
PB21C
PB21B
PB21A
PB19B
PB19A
PB19D
PB19C
PB18D
PB18C
PB18B
PB18A
PB16B||PCLKC2_1
PB16A||PCLKT2_1
PB16D
PB16C
PB12D
PB12C
PB12B
PB12A
PB11B||PCLKC2_0
PB11A||PCLKT2_0
PB11D
PB11C
PB9D
PB9C
21
21 21
21
21 21
21 21
21 21
21
21
21
21
21 21
21
21
21
21
SHEETDATE
DEPARTMENT
SIZE
PROJECT DOCUMENT NUMBER REV
REVIEWER
DESIGNER
123
7 3 2 1 6 5 4
E
A
B
C
E
D
C
B
A
7 6 5 4
D
IN
ININ
ININ
IN
ININ
ININ
ININ
OUTOUT
INBI
IN
IN
IN
OUTOUT
ININ
ININ
OUT
ININ
OUTIN
IN
OUTIN
IN
C



Fri Aug 25 17:25:44 2023<NAME_2><NAME_1>NANANA37 OF 60FPGA 4/8
VCCIO3SMLFICLCMXO3LF-2100C-5BG256CAJ021000T03
M4
P2
R1
N3
M2
P1
N2
N1
M3
L4
K5
M1
L2
L5
K4
L3
L1
U25
4/7
BANK3
PL13B
PL13A
PL13D
PL13C
VCCIO3
PL14D
PL14C
PL14B
PL14A
PL12B||PCLKC3_0
PL12A||PCLKT3_0
PL12D
PL12C
PL11D
PL11C
PL11B
PL11A
SHEETDATE
DEPARTMENT
SIZE
PROJECT DOCUMENT NUMBER REV
REVIEWER
DESIGNER
123
7 3 2 1 6 5 4
E
A
B
C
E
D
C
B
A
7 6 5 4
D
C



Fri Aug 25 17:25:44 2023<NAME_2><NAME_1>NANANA38 OF 60FPGA 5/8
VCCIO4LCMXO3LF-2100C-5BG256CSMLFICAJ021000T03
J7
H7
K6
J5
K2
K3
J4
H5
K1
J2
J3
J1
H1
H3
J6
H4
H2
G1
U25
5/7
BANK4
VCCIO4_J7
VCCIO4_H7
PL9D
PL9C
PL9B
PL9A
PL10B
PL10A
PL10D
PL10C
PL7D||PCLKC4_0
PL7C||PCLKT4_0
PL7B
PL7A
PL6D
PL6C
PL6B
PL6A
SHEETDATE
DEPARTMENT
SIZE
PROJECT DOCUMENT NUMBER REV
REVIEWER
DESIGNER
123
7 3 2 1 6 5 4
E
A
B
C
E
D
C
B
A
7 6 5 4
D
C



Fri Aug 25 17:25:45 2023<NAME_2><NAME_1>NANANA39 OF 60FPGA 6/8
VCCIO5SMLFICLCMXO3LF-2100C-5BG256CAJ021000T03
E4
H6
F5
G3
G2
G4
G5
F1
F3
G6
F4
F2
E1
D2
C1
E3
E2
C2
B1
D1
D3
U25
6/7
BANK5
PL4B
PL4A
PL4D
PL4C
VCCIO5
PL5D
PL5C
PL5B
PL5A
PL3D
PL3C
PL3B||PCLKC5_0
PL3A||PCLKT5_0
PL2D
PL2C
PL2B||L_GPLLC_IN
PL2A||L_GPLLT_IN
PL1B||L_GPLLC_FB
PL1A||L_GPLLT_FB
PL1D
PL1C
SHEETDATE
DEPARTMENT
SIZE
PROJECT DOCUMENT NUMBER REV
REVIEWER
DESIGNER
123
7 3 2 1 6 5 4
E
A
B
C
E
D
C
B
A
7 6 5 4
D
C



Fri Aug 25 17:25:45 2023<NAME_2><NAME_1>NANANA40 OF 60FPGA 7/8
PVCCA_AUX_PLDLCMXO3LF-2100C-5BG256CSMLFICAJ021000T03
T16
T1
K10
K7
G10
G7
A16
A1
A2
R15
R2
P14
P3
N13
N4
M12
M5
L11
L6
J9
J8
H9
H8
F11
F6
E12
E5
D13
D4
C14
C3
B15
B2
U25
7/7
VCC_A1
VCC_A16
VCC_G7
VCC_G10
VCC_K7
VCC_K10
VCC_T1
VCC_T16
NC1
GND_R15
GND_R2
GND_P14
GND_P3
GND_N13
GND_N4
GND_M12
GND_M5
GND_L11
GND_L6
GND_J9
GND_J8
GND_H9
GND_H8
GND_F11
GND_F6
GND_E12
GND_E5
GND_D13
GND_D4
GND_C14
GND_C3
GND_B15
GND_B2
SHEETDATE
DEPARTMENT
SIZE
PROJECT DOCUMENT NUMBER REV
REVIEWER
DESIGNER
123
7 3 2 1 6 5 4
E
A
B
C
E
D
C
B
A
7 6 5 4
D
C



120OHMFri Aug 25 17:25:45 2023<NAME_2><NAME_1>NANANA41 OF 60FPGA 8/8
VCCIO2PVCCA_AUX_PLDVCCIO4P3V3_AUXVCCIO3VCCIO1VCCIO0P3V3_AUXP3V3_AUXP3V3_AUXVCCIO5
P3V3_AUXP3V3_AUX
P3V3_AUX
0402EMPTYEMPTYCH31006KB18C04020.01UF10%EMPTYCH31006KB180.1UFCH4104K1B00CH31006KB18C0402EMPTY0.01UFCH31006KB180.1UFCH4104K1B000402CH4104K1B000.1UF0402CH5104KEB021UF25VCH5104KEB0210%X6SC0402CS00002JB13CS00002JB130402LFCHIP1/16W0402X7R10%0.01UF10%50VC040250V0.01UF10%50V0402LFCHIP25V0402X6S10%20%X6S
10%X7R0.1UF025V10%X7R040205%1/16W CHIP 0402LFCS00002JB1301/16W 0402LF1/16W CHIP 0402LF040210%25V1UFX6S10%CH4104K1B0025V0.1UF5%040210%X7R25VCS00002JB130402LFCHIP1/16W5%0CS00002JB131/16W5%0040225V10%X7R0.1UF25V1UF0.1UFX6S25V1UF25V10%X6S25V05%1UFX6SCHIP5%CS00002JB130.1UFCH4104K1B00C04021UF10%CH5104KEB02C0402C04020.1UFC0402C0402040210%25V10UF16VCH6103ME902C06030.1UF25V10%X7RCH5104KEB02X7R0402X7RCH4104K1B0010%25V10%25V0.1UFCH4104K1B0025V10%X7R0.1UFX7R04020.1UF25VCH4104K1B0010%25VX7R0402CH4104K1B0025V0.1UFX7R0402CH4104K1B0010%0.1UF25V10%X7R0402X7R25V0402CH4104K1B000.1UF10%0402CH4104K1B0025V10%X7R0.1UFCH4104K1B00CH4104K1B00CH5104KEB02C040210%50V10%X7R0402CH4104K1B0025VX7R10%25V0.1UFCH4104K1B0004020.1UF0402CH4104K1B0010%X7R25VCH4104K1B00040225V0.1UF0402X7R0.1UF25V10% 10%X7RCH4104K1B00INDSMLFCX8EG121000BLM18EG121SN1D/2A10UFX6S20%16V1UFX6SCH5104KEB0225V10%X7R0.1UF25V10%C0402CH6103ME902C0603C0402CH5104KEB02X6S10%25V1UFCH5104KEB02CH4104K1B00CH4104K1B00X7RCH4104K1B0010%
L19
R305
1 2
2
1
2
1
2
1
2
1
2
1
2
1
2
1
2
1
2
1
2
1
2
1
2
1
2
1
2
1
2
1
2
1
2
1
2
1
2
1
2
1
2
1
2
1
2
1
2
1
2
1
2
1
2
1
2
1
2
1
2
1
2
1
2
1
2
1
2
1
21
21
21
21
21
2
1
2
1
21
SHEETDATE
DEPARTMENT
SIZE
PROJECT DOCUMENT NUMBER REV
REVIEWER
DESIGNER
123
7 3 2 1 6 5 4
E
A
B
C
E
D
C
B
A
7 6 5 4
D
C283
C281
C285
C286C163 C266 C269 C263C190C250C193C176
C194
C145
C195
C218
C216
C165
C164
C162C220
C160
C152
C260C188C245C187
C141C254C243C167
C261C189C247
R307
R301
R308
R304
R525
C166 C242
C



DESIGN NOTE:FM_JTAG_BMC_MUX_SEL == LOW (DEFAULT) , BMC TO CPLD.FM_JTAG_BMC_MUX_SEL == HIGH , BMC TO CPU/PCH.Fri Aug 25 17:25:45 2023<NAME_2><NAME_1>NANANA42 OF 60BMC/FPGA GPIO PU
P3V3_AUXP3V3_AUX4.7KCHIPFM_ADR_TRIGGER_N35
CHIPFM_JTAG_BMC_MUX_SELPWRGD_DSW_PWROKFM_BMC_CRASHLOG_TRIG_NFM_P12V_HSC_ENABLEBMC_CPLD_GPIO_8BMC_CPLD_GPIO_7BMC_ID_BEEP_SELBMC_CPLD_GPIO_2EMPTY4.7KCHIPBMC_CPLD_GPIO_12BMC_CPLD_GPIO_134.7KCHIP4.7KEMPTY
EMPTY4.7K4.7KCHIPCHIP4.7KRST_BMC_SELF_HW_R2
4.7K CHIP491336153613281336353515353415
3535313413
4.7K4.7K100K4.7KCHIPCHIPEMPTY4.7K
R319
R835
R749
R642
R640
R641
R593
R595
R607
R608
R621
R627
21
SHEETDATE
DEPARTMENT
SIZE
PROJECT DOCUMENT NUMBER REV
REVIEWER
DESIGNER
123
7 3 2 1 6 5 4
E
A
B
C
E
D
C
B
A
7 6 5 4
D
OUT
OUT
OUT
OUT
OUT
OUT
OUT
OUT
OUT
OUT
OUT
OUT
R586
C



Fri Aug 25 17:25:46 2023<NAME_2><NAME_1>NANANA43 OF 60BLANK PAGE
SHEETDATE
DEPARTMENT
SIZE
PROJECT DOCUMENT NUMBER REV
REVIEWER
DESIGNER
123
7 3 2 1 6 5 4
E
A
B
C
E
D
C
B
A
7 6 5 4
D
C



TO BIOS MUXFROM BMCFROM BMCFROM PCH TO TPMTO BIOS MUXFROM PCHTO BIOS MUX
Fri Aug 25 17:25:46 2023<NAME_2><NAME_1>NANANA44 OF 60SPI - BIOS FLASH MEMORY MUXSPI_PCH_MUXED_IO2SPI_PCH_MUXED_IO1SPI_PCH_MUXED_CS0_NSPI_PCH_MUXED_IO0SPI_BMC_BIOS_ROM_R_IO3SPI_BMC_BIOS_ROM_R_MOSISPI_SYS_MUX_MOSI44SPI_SYS_MUX_HOLD_IO3SPI_SYS_MUX_WP_IO2SPI_SYS_MUX_MISOSPI_SYS_MUX_MOSISPI_SYS_MUX_CLKSPI_BMC_BIOS_CS0_NSPI_BMC_BIOS_ROM_IO3SPI_BMC_BIOS_ROM_IO2FM_BMC_BIOS_MUX_CS_SPI_R_SEL_0PD_BIOS_MUX_EN_NSPI_PCH_SECURE_CS0_NSPI_PCH_MUXED_CLKTP_BIOS_MUX1_PIN120402CH4104K1B0025V0.1UF0402LF4.7K0402LF10KCHIP1/16W1%ICX7RCH4104K1B000.1UF10%040225V10%X7RSPI_SYS_MUX_CLKSPI_SYS_MUX_HOLD_IO3IDTQS3VH257PAGSPI_BMC_BIOS_ROM_R_CLK33.233.233.2 CHIPCHIPCHIP33.2 CHIP33.2 CHIPCHIP2222SPI_PCH_SECURE_CS0_NSPI_SYS_MUX_MISO1%1/16WTP_BIOS_MUX0_PIN12SPI_PCH_MUXED_IO3AL000257K001310104610441344444545454510131313131313444444444410444444444444101044444444444545SPI_TPM_CS_NFM_BMC_MUX_CS_SPI_SEL_0CHIP33.24646SPI_BMC_BIOS_ROM_CLKSPI_BMC_BIOS_ROM_MOSISPI_BMC_BIOS_ROM_MISO44444444SPI_BMC_BIOS_SOURCE_CS0_NSPI_BMC_BIOS_ROM_R_IO3SPI_BMC_BIOS_ROM_R_MOSISPI_BMC_BIOS_ROM_R_MISOSPI_BMC_BIOS_ROM_R_IO2CS00002JB13022CHIP33.2CHIP2233.2CS02202FB02CHIPCHIPCHIPCHIPCHIP464444441/16WCHIP0402LFCS31002FB08EMPTYCS24702FB06ICAL000257K00IDTQS3VH257PAGTP_BIOS_MUX0_PIN14TP_BIOS_MUX0_PIN1344SPI_BMC_BIOS_ROM_R_CLKCS06812FB0368.113SPI_BMC_BIOS_ROM_R_IO2SPI_SYS_MUX_WP_IO2SPI_BMC_BIOS_ROM_R_MISOSPI_BMC_BIOS_SOURCE_CS0_NTP_BIOS_MUX1_PIN13TP_BIOS_MUX1_PIN142K1%PD_BIOS_MUX_EN_NFM_BMC_BIOS_MUX_CS_SPI_R_SEL_044FM_BMC_BIOS_MUX_CS_SPI_R_SEL_0SPI_TPM_CS_R_NSPI_SYS_CS0_NSPI_SYS_HOLD_R_IO3SPI_SYS_WP_R_IO2SPI_SYS_R_MISOSPI_SYS_R_MOSISPI_SYS_R_CLK
VCC
YB
I_1D
I_0D
I_0C
I_1C
I_0B
I_1B
I_1A
I_0A
S
YD
YC
YA
E_N
GND
VCC
YB
I_1D
I_0D
I_0C
I_1C
I_0B
I_1B
I_1A
I_0A
S
YD
YC
YA
E_N
GND
R594
R864
R859
R728
R725
R724
R176
R174
R175
R870 R467
R866
U21
C146
C255
U30
21R852
21 21 21 21
R863R862R861R860
21
21
21
21
12
9
7
4
16
1
13
10
6
3
14
11
5
2
8
15
2
1
2
1
12
9
7
4
16
1
13
10
6
3
14
11
5
2
8
15
SHEETDATE
DEPARTMENT
SIZE
PROJECT DOCUMENT NUMBER REV
REVIEWER
DESIGNER
123
7 3 2 1 6 5 4
E
A
B
C
E
D
C
B
A
7 6 5 4
D
IN OUT
IN OUT
INININOUTININ
IN
ININOUTININ
OUT
OUT
OUT
INOUT
OUT
OUT
IN
OUTOUT
OUTOUT
P3V3_AUX
ININ
IN
IN
P3V3_AUX
OUT
OUT
OUT
ININ
OUTOUT
ININ
ININ
ININ
P3V3_AUX
OUT
OUT
OUT
IN
IN
C



NOTE:BIOS ROM HAS THE INTERNAL PU FOR PIN3
Fri Aug 25 17:25:46 2023<NAME_2><NAME_1>NANANA45 OF 60PCH BIOS ROM
P3V3_AUXP3V3_AUXP3V3_AUXTP_J40_14TP_J40_13TP_J40_4EMPTYAKE3FF00Z00MX25L51245GMI-10GSCONN16_ACA-SPI-006-P06SOCKET PN: DG016000006SMLFPLACE PU RES CLOSE TO FLASH ICRST_SPI_PCH_FLASH_R1_NTP_J40_5TP_J40_5TP_J40_14TP_J40_13TP_J40_12SPI_PCH_CLK_FLASH_R1SPI_PCH_IO0_FLASH_R1CHIPCHIP33.21%4.7KFLASH PN: AKE3FF00Z00(MX25L51245GMI-10G) SOIC16DG016000006IOSPI_PCH_IO2_FLASH_R1SPI_PCH_IO1_FLASH_R1SPI_PCH_CS0_FLASH_R1_NSPI_PCH_IO3_FLASH_R14.7K1%EMPTYPLACE CAP CLOSE TO PIN VCC44 TP_J40_6TP_J40_11TP_J40_12TP_J40_4TP_J40_6TP_J40_110402LFEMPTYSMLFCS24702FB064.7KCH5104KEB021%50V512MBIT(64MBYTE)25VC040210%1UFX6SCH31006KB18C040210%0.01UFX7RCS24702FB06444444440402LF33.2 CHIPCHIP33.233.2 CHIP33.2CHIP33.2CHIPCHIP4.7K1%CHIP4.7K1%SPI_PCH_MUXED_CLKSPI_PCH_MUXED_IO0SPI_PCH_MUXED_IO2SPI_PCH_MUXED_IO1SPI_PCH_MUXED_CS0_NSPI_PCH_MUXED_IO344 4545454545454545454545454545
9
2
8
15
16
3
1
14
13
4
10
12
11
6
5
7
9
2
14
13
12
11
6
5
4
3
1 10
8
15
7
16
R487
R496
C246C244
R492R490R488
R481
R483
R482
R484
R485
R486
U17
J40
SCLK
SI_SIO0
NC3
NC2
DNU4
DNU3
GND
WP#_SIO2
SO_SIO1
CS#
DNU2
DNU1
NC1
RESET#
VCC
NC_SIO3
NC8
NC7
NC6
NC4
NC3
NC2
NC1
NC0DO
GND
CLK
DI
WP_N
CS_N
HOLD_N
VCC
CAD NOTE: BOM NOTE:
CAD NOTE:
2
1
2
1
2
1
2
1
2
1
2
1
2
1
SHEETDATE
DEPARTMENT
SIZE
PROJECT DOCUMENT NUMBER REV
REVIEWER
DESIGNER
123
7 3 2 1 6 5 4
E
A
B
C
E
D
C
B
A
7 6 5 4
D
BIBI
BI
BI
IN
IN
C



PCH TPM
BMC TPMFri Aug 25 17:25:47 2023<NAME_2><NAME_1>NANANA46 OF 60TPM2.0 CONNP3V3_AUXP3V3_AUXP3V3_AUXP3V3_AUXP3V3_AUX P3V3_AUXP3V3_AUXP3V3_AUXP3V3_AUX5%5%5%05%33.2CHIPCHIP000SPI_BMC_TPM_CLKRST_BMC_EXTRST_R2_NSPI_BMC_TPM_CS2_R_N SPI_BMC_TPM_CS2_N_R
33.2 CHIP5%CS31002FB081/16W33.2SPI_BMC_TPM_MISOSPI_BMC_TPM_MOSI13SCONN11_91920-31111LF1/16W1/16WCHIPCHIP
1/16W1%10K
SMB_BMC_MM16_R5_SDACHIPCHIPSMLFEMPTY4.7KEMPTY132713132236 3421 120402LF 1/16WCS03322FB03SMB_BMC_TPM_MM16_SCLIRQ_BMC_TPM_SPI_R_NFM_TPM_PRSNT_1_N1/16WCHIPCS31002FB08SMB_BMC_MM16_R5_SCLIRQ_TPM_SPI_N0402LFCS31002FB08CHIP1/16W1%10K1%0402LF1%10K0402CH4104K1B006.3V0.1UF25VIRQ_PCH_TPM_SPI_NFM_TPM_PRSNT_0_NIRQ_PCH_TPM_SPI_R_N0CHIPSMB_PCH_TPM_SCL10K1%0402LF1/16WCHIPCS31002FB080402LFCS31002FB08CHIP0402LFCS31002FB08CHIP10K1%1/16W10%6.3VSPI_SYS_R1_CLKRST_PLTRST_TPM_N22CHIPSPI_SYS_R_MISOSPI_SYS_R_MOSI0CHIPCS02202FB02CS02202FB02SPI_SYS_R1_MOSISPI_SYS_R1_MISORST_PLTRST_NSPI_TPM_CS_R_NDFHS11FS009DFHS11FS009IO0402LF0402LF0402LF0402LFSMB_BMC_TPM_MM16_SDA
1534441010441044101112283444 153615 3412 2134 36130CHIP220SPI_SYS_R_CLKCHIP 1/16W 0402LFSPI_TPM_CS_N_RCH6101MEB01IOCH4104K1B00SMLFSCONN11_91920-31111LFX7R10%0.1UFX6S20%CH6101MEB01C0402X6S20%10UFC04021%CHIP10K10UF25VSMB_PCH_TPM_SDA0402LF4.7KSPI_BMC_TPM_MISO_RSPI_BMC_TPM_MOSI_RCHIP33.2RST_BMC_EXTRST_R3_N1/16WSPI_BMC_TPM_CLK_R
X7R1/16W0402
CHIP
R100
R408
R126
R136
R98
R33
R110
R97
R109
G2
G1
11
10
9
8
7
6
5
4
3
2
1
J10
C143
R47
R113
R50
C144
R59
R497R464
R505
C248 C249
R500
R503
R501
G2
G1
11
10
9
8
7
6
5
4
3
2
1
J5
11
10
9
8
7
6
G2
G1
2
5
4
3
1
11
10
9
8
7
6
G2
G1
2
5
4
3
1
2 1
2
1
R414
2
1
21 21R498R499
21
21
2 1
2 1
2 12 1
SHEETDATE
DEPARTMENT
SIZE
PROJECT DOCUMENT NUMBER REV
REVIEWER
DESIGNER
123
7 3 2 1 6 5 4
E
A
B
C
E
D
C
B
A
7 6 5 4
D
OUT
OUTIN
IN
OUTOUT
IN
IN
IN
BIINOUTINININ OUT
C



PORT 80
IF RATING=25MALED RED VF=1.2V(TBD)~2.4VSHOULD BE ARRANGE ACCORDING TO THE ORDER D0~D3 D4~D7IF=(3.3V-VF)/750 OHM=1.2MA~2.8MAIF=(3.3V-VF)/750 OHM=1.27MA~2.07MAIF RATING=25MALED GREEN VF=1.75V~2.35VFri Aug 25 17:25:47 2023<NAME_2><NAME_1>NANANA47 OF 60LED PORT-80
28282828282828281313131313131313BEGR0278Z00LED_GREENBEGR0278Z00LED_POSTCODE_0_RLED_POSTCODE_1_R0402LF1/16WCHIPCS17502FB030402LFCHIP1/16W1%750CS17502FB030402LFCHIP1/16W1%750CS17502FB03LED_POSTCODE_2_R0402LFCHIP1/16W1%750CS17502FB03LED_POSTCODE_3_R0402LFCHIP1/16W1%750CS17502FB03LED_POSTCODE_4_R0402LFCHIP1/16W1%750CS17502FB03LED_POSTCODE_5_R0402LFCHIP1/16W1%750CS17502FB03LED_POSTCODE_6_R0402LFCHIP1/16W1%750CS17502FB03LED_POSTCODE_7_R0402LFCHIP1/16W1%750LED_POSTCODE_5_R10402LFCHIP 1/16W5%0LED_POSTCODE_6_R10402LFCHIP 1/16W5%0LED_POSTCODE_7_R10402LFCHIP 1/16W5%0LED_POSTCODE_0_R10402LFCHIP 1/16W5%0LED_POSTCODE_1_R15%0LED_POSTCODE_2_R10402LFCHIP 1/16W5%0LED_POSTCODE_3_R10402LFCHIP 1/16W5%0LED_POSTCODE_4_R10402LFCHIP 1/16W5%0LED_REDLED_REDLED_REDICSMLFLED_POSTCODE_4LED_POSTCODE_3ICBERD0034Z07SMLFBERD0034Z07ICBEGR0278Z00SMLFLED_GREENICBERD0034Z07LED_REDICBERD0034Z07LED_GREENICSMLFICSMLFLED_GREENICBEGR0278Z00SMLFLED_POSTCODE_7LED_POSTCODE_6LED_POSTCODE_5LED_POSTCODE_2LED_POSTCODE_1LED_POSTCODE_0SMLFSMLF
R700
R698
R697
R696
R695
R676
R674
R669
R604
R603
R602
R601
R600
R599
R598
R597
CA
D6
CA
D3
CA
D5
CA
D2
CA
D4
CA
D1
CA
D0
CA
D7
A C
A C
A C
A C
A C
A C
A C
A C
SHEETDATE
DEPARTMENT
SIZE
PROJECT DOCUMENT NUMBER REV
REVIEWER
DESIGNER
123
7 3 2 1 6 5 4
E
A
B
C
E
D
C
B
A
7 6 5 4
D
OUT
OUT
OUT
OUT
OUT
OUT
OUT
OUT
IN
IN
IN
IN
IN
IN
IN
IN
C



VCC : ENABLE PROGRAMING(DEFAULT)GND : DISABLE PROGRAMINGMB_JTAG_PLD_R_JTAGEN : JTAGENVCC : (DEFAULT)GND : BMC DEBUGFM_BMC_DEBUG_SW_N : BMC/BIOS DEBUG SWITCHGND : TCK TO CPU(DEFAULT)VCC : TCK TO PCHFM_JTAG_TCK_MUX_BMC_SEL_R : JTAG TCK SELFLOAT : ENABLE BMC(DEFAULT)GND : DISABLE BMCFM_BMC_DISABLE : BMC DISABLE
Fri Aug 25 17:25:47 2023<NAME_2><NAME_1>NANANA48 OF 60DEBUG HEADERS(SWITCH)P3V3_AUX
P3V3_AUXP3V3_AUXP3V3_AUX343233.2CS11002FB070402LFEMPTYEMPTYCHIP1%CS31002FB080402LFMB_JTAG_PLD_R_JTAGENCS11002FB07CHIP1/16WFM_JTAG_TCK_MUX_BMC_SEL_RCHIPFM_JTAG_TCK_MUX_BMC_SELEMPTYFM_BMC_DISABLEEMPTY0402LF4.7K1%13361336
270402LF100K1%1/16WCS41002FB090402LFJTAG_SCM_PLD_JTAGEN1001%FM_BMC_DEBUG_SW_N1001%0402LF1%10KCHIP1/16W0402LF00402LFEMPTY1/16W4.7KCHIP
1/16W4.7K1%CS11002FB071/16W1%100
R431
R506 R507
R508
R509
R624
R616
R620
R615
2
1
2
1
2
1
2
1
2
1
2
1
SHEETDATE
DEPARTMENT
SIZE
PROJECT DOCUMENT NUMBER REV
REVIEWER
DESIGNER
123
7 3 2 1 6 5 4
E
A
B
C
E
D
C
B
A
7 6 5 4
D
OUT
OUT
OUT
OUT
R881
C



UART LEDID LED
PWR LEDHDD LEDFri Aug 25 17:25:47 2023<NAME_2><NAME_1>NANANA49 OF 60LED
P5V_AUXP3V3_AUXP3V3_AUXP3V3_AUXP3V3_AUXP5V_AUXID_LED_D_P3V3_AUXICBEYL0182D00ID_LED_P3V3_AUXLED_YELLOWLTL-R42FSFADH213TTHLF0402LFCS12202FB04AL1G0126009ICCHIPLED_BLUEHV-312470/260/SUBD-TR11%
1/16WCHIPCS12202FB040402LFBMC_ID_BEEP_SEL74LVC1G126SE-7AL001G32031MC74VHC1G32DTT1GSMLF1%THLFIC0402LFPWR_LED_BUF_N_R1%1%CS12202FB04ICBEBL0277D00HDD_LED_BUF_RTHLFPWR_LED_P5V_AUX50V10%X7R0402TMP_QCH14706KB180402LF2200402X7R10%25V0.1UF470PF
10
491049 3630304942
49153510KCHIP1%CHIP33.21/16WPWR_LED_BUF_NCS07502FB041%75FM_UARTSW_LSB_NBEBL0172Z00LTST-C281TBKT-5AICIC10%
33.2IC10KSMLF
8.2K5%1/16WCHIPCS28202JB050402LF25V0402CH4104K1B0010%
CH4104K1B0025VX7R0402
HDD_LED_BUF
10%SMLFBEEP_LED0.1UF
10%
0.1UF
2N7002KDW
CHIP1/16W1% SMLFLED_BLUESMLFLTST-C281TBKT-5A25V
04021/16WBEBL0172Z00IC
5%8.2KX7R X7R0402LFSMLF50VPWR_LED_BUF_NPWR_LED
13FM_ID_LED1333.2CHIP1/16WNET PWR_LEDIS SHARED WITH NET PWRGD_SYS_PWROKSWITCH INSIDE FPGATO ACHIEVE PWR LED FUNCTIONCS28202JB05EMPTYBAM70020047ICCHIP0402LFCS31002FB0810K1/16WCHIPPCH_BEEP_LED
1/16W1/16WCHIP 0402LFCS07502FB04BAM138K00030402LFFM_ID_R_LEDX7R0402CH4104K1B00LED_BLUE
2200.1UF1/16W751%FM_UARTSW_MSB_R1_N220CHIPPJT138KID_LED_BUF470PFHDD_LED_NHDD_LED_BUFCHIPFM_UARTSW_MSB_N36HDD_LED_P5V_AUXHV-312470/260/SUBD-TR1LED_BLUEBEBL0277D00FM_UARTSW_LSB_R1_N0402LF
G1
D1S1
C276
C A
C A
C A
R390
C A
C A
C197C321
R815
C326C324
R814
R813
R812
R619
41
52
36
Q12
R839
C274
4
1
2
R306
2
5
4
1
2
3
531 6
D13
D15
D14 D18
D19
U8
Q9
U9
AC
AC
AC AC
AC
VCC
GND
IN_A
IN_B
OUT_Y
D2D1
S2S1
G2G1
OE
Y
A
R43R56921R568GND VCC
21
21R284
21
2
1
2
1
DESIGN NOTE:
2121
R283
2
1
2
1
2
1
2
1
2
1
2
1
21
21
2
1
2
1
2
1
SHEETDATE
DEPARTMENT
SIZE
PROJECT DOCUMENT NUMBER REV
REVIEWER
DESIGNER
123
7 3 2 1 6 5 4
E
A
B
C
E
D
C
B
A
7 6 5 4
D
IN
IN
IN
IN
IN
IN
OUTININOUT
IN
C



AC POWER BUTTONADD AC POWER BUTTON_20220804BATTERYPOWER BUTTONADD LED_20220804RESET BUTTONSCM VIN LEDP1V0 PWRGD LEDFri Aug 25 17:25:48 2023<NAME_2><NAME_1>NANANA50 OF 60PWR BTN & BATTERY
P3V3_RTC_AUXP3V3_AUXP3V3_AUXP3V3_AUXP3V3_AUX P3V3_AUXP3V3_AUXP12V_AUXP5V_AUXP3V3_AUXP3V3_AUXP3V3_AUX316C0402C040225V
AC_PWR_BTN_R1_NNC_U16_P110111511101011EMPTY10%25V0.1UFCH4104K1B000402EMPTYALVC1G07002SMLF74LVC1G07GWCHIP0SMLFUCLAMP0511TX7R10%8.2K5%1/16WEMPTYCS28202JB050402LF1UF0ICALVC1G07002SMLF0.1UFX7R040225VCHIP01UF25V10%X6S3434151534CHIP1510%25V0402LFREAR_ID_RST_BTN_NTP_PWR_BUF0CHIP1%PWRGD_P1V0_AUX_DELAY
10%X7R25V04021/16W5%8.2KC040210%X6S25V1011
1%IC22
CHIP
0.1UF040210%X7RCH4104K1B001%10%28 C0402ICBAS70-05-7-FBC0BAS70Z01SMLF10P3V_BAT_R1UF25V10%X6SIC1534X7R5%CHIP1/16WCS28202JB051UFX6S25V1UF15PWR_BTN_BMC_NALVC1G070020.1UF8.2K028FM_DEBUG_PWR_BTN_NCH5104KEB02
BAM138K0003ICBC00511TZ00EMPTYREAR_AC_PWR_BTN_NAC_PWR_BTN_N25V0.1UFREAR_AC_PWR_BTN25VCS13162FB0131610%74LVC1G07GW
SMLF74LVC1G07GW0402CH4104K1B00ICCS13162FB011%CS13162FB01LED_D21_R20402LF1/16WC04020.1UFSMLF74LVC1G17GWAL1G0017K01ID_RST_BTN_BMC_NLED_D21_R11/16W316CHIP0402LF1/16W CHIP220CS12202FB04CHIPNC_U57_P1AC_PWR_BMC_BTN_ND10 CHANGE TO BC8231ADZ01
0402LF1/16W0402LFCH4104K1B000402LFCS28202JB05CHIPSW4S_DTSAM-63N/K-S-Q-T/RSMLFMECHDHPDTSAM601SW4S_DTSAM-63N/K-S-Q-T/RSMLFMECHDHPDTSAM601REAR_PWR_BTN_NFM_DEBUG_RST_BTN_NSMLFMECHLED_D21_R3LED_BLUEHV-312470/260/SUBD-TR1THLFICBEBL0277D00LED_BLUEHV-312470/260/SUBD-TR1THLFICBEBL0277D00LED_D22_R1LED_D22_RSMLFPJT138K
TP_ID_BUFREAR_AC_PWR_BMC_BTN_NCH4104K1B008.2K5%0402LF1/16WCS28202JB050402CH4104K1B00EMPTYEMPTY10%SW4S_DTSAM-63N/K-S-Q-T/RDHPDTSAM601
G1
D1S1
C A
C A
43
21
43
21
R882
C335
R883
C336
4
5
13
2
U57
C181
CA
R470
C28
R391
C29
4
5
13
2
U16
2
C27
43
21
3
1
2
R733
R734
4
5
13
2
U31
R768
R504
C199
C201
4
5
13
2
U32
C198
C200
1 6
D22
D21
SW8
SW6
D10
Q13
SW7
U48
NC
Y
GND
A
VCC
AC
AC
43
21
43
21
NC
Y
GND
A
VCC
CA
NC
Y
GND
A
VCC
43
21
C
A
B
NC
Y
GND
A
VCC
R80
21
2
1
21
21
212121
2
1
BOM NOTE:
21
2
1
2
1
2
1
2
1
2
1
2
1
R107
2
1
2
1
2
1
2
1
2
1
2
1
2
1
SHEETDATE
DEPARTMENT
SIZE
PROJECT DOCUMENT NUMBER REV
REVIEWER
DESIGNER
123
7 3 2 1 6 5 4
E
A
B
C
E
D
C
B
A
7 6 5 4
D
OUT
OUT
OUT
OUT
OUT
IN
IN
OUT
OUT
R471
R389R286
C196
C



IC TABLE
P5V_AUXOUTPUT RIPPLE=1%OUTPUT VOLTAGE=5VDESIGN SPECIFICATIONCURRENT STEP=1.7ATRANSIENT TOLERANCE=+/-5%OVER CURRENT=3AMAX CURRENT=1.7ATDC=1.4ASLEW RATE=0.25A/USWORK FREQUENCY=600KHZP3V3_LDOTO POWER LOGIC FOR BMC SEQUENCE
1ST AL0086330072ND AL053318002Fri Aug 25 17:25:48 2023<NAME_2><NAME_1>NANANA51 OF 60MPQ8633A - P5V_AUX
P3V3_LDOP12V_AUXP12V_AUXP5V_AUX_VCCP5V_AUX
P12V_AUX
10%X7REN_P5V_AUX SW_P5V_AUX_SW0402CH4223K1B0012.4K1/16W CHIP1/16W0CS00002JB13THE CAP & DAMPING RS FOR PWRGD SHOULD CLOSE TO DRIVE-ENDEMPTYEN_P3V3_R10402LFPWRGD_P5V_AUX0402LFCHIP1/16WPWRGD_P5V_AUX_RCS41002FB09EMPTY10%X7RP5V_AUX_REFCH5104KEB02C0402P5V_AUX_CS0402LFCS32052FB0225V0.1UFC0805CH6222MEA00X6S20%10V22UF5%CS00002JB13C0805CH6223MEA01CH6223MEA01C0805BLM18SN220TN1D/8000MAINDCH4104K1B00SMLFCX220TN1001AP2205-W5-7SMLFX7RMPQ8633AGLE-C807-ZAL008633007SW_P5V_AUX_FLTSW_P5V_AUX_BSTP5V_AUX_FBX7RCH4104K1B0025V040210%0.1UF681K1%1/16WCHIPCS46812FB060402LF0.1UF0402CS41002FB091%1/16WCHIP0402LF100K1UFX6S16V20%22UFX6S20%22UF16V20.5K1%1/16WCHIP68PFC040250VCOG5%CH06806JB01CH4104K1B0004021%1/16WCHIPCS31242FB020.22UF16V1%10KX7R10%25V0.1UFISAT=13AX6S20%C0805CH6222MEA0010VX6S20%22UF5%10VX6S20%CH6222MEA00C080522UF01/16W1%100KICSMLFP5V_AUX_VCC VOLTAGE LEVEL IS 3V3C04021UF25V10%X6SU56_ADJ_10402LFSMLFDCR=13.2MOHM0402LFCH4104K1B0010V22UF10%EMPTYCH30106KB19C0402IND25V10% 565554523552AL002205001IC10KCH5104KEB02
04024.7UHCV-47A0MZ1050V0.001UF0402LFCS31002FB08CHIP1/16WCH6222MEA00C08050402LFCS39102FB061%91K10%25VX6SP5V_AUX_VCC
CHIP0402CH4104K1B00X7R10%25V0.1UF0402LFCHIPCS31002FB081/16W1%16.9KC0402CH5222KEB01CS31692FB030402LF1/16W1%X6S10%10V2.2UF
51
2
3
4
C241
PC207PC206 PC210
PR24521
10
19
5
20
6
9
11_18
4
7
8
3
1
2
PU38
PL4
PC217PC215PC214PC213PC212
PR527
21
PL34
PC272
PR526
PC216
PC271
PR241
PC208
PR525
PR521
PR522PC205
U56
EN
GND
VIN
ADJ||NC
VOUT
VIN2
CS
MODE
TRK_REF
SW
RGND
VCC
AGND
FB
BST
EN
PGND
PGOODVIN1
1 2
1 2
2
1
2
1
R631
2
1
2
1
R677
21
2
1
21
2
1C150
DESIGN NOTE:
CAD NOTE:
C226
2
1
2
1
2
1
21
2
1
2
1
2
1
2
1
2
1
2
1
2
1
2
1
2
1
2
1
SHEETDATE
DEPARTMENT
SIZE
PROJECT DOCUMENT NUMBER REV
REVIEWER
DESIGNER
123
7 3 2 1 6 5 4
E
A
B
C
E
D
C
B
A
7 6 5 4
D
OUT
OUT
C227
R868
R292
C



CHANGE TO 2.2K_20220426FOR BMC POWER DOMAIN: P3V3_RGMCHANGE TO 2R2_20220804MAX CURRENT=4.1ATDC=3.6ATRANSIENT TOLERANCE=+/-5%OUTPUT RIPPLE=+/-1%IC TABLE1ST AL0086260002ND AL053317005SLEW RATE=0.25A/USCURRENT STEP=0.9AOUTPUT VOLTAGE=3.3VDESIGN SPECIFICATIONOVER CURRENT PROTECTION(IC RATING)=6AWORK FREQUENCY=600KHZ
PWRGD_UP DELAY 230US
P3V3_AUXDCR=28MOHMISAT=13.5A6.5*6.9*3.0PCMC063T_3R3MN
Fri Aug 25 17:25:48 2023<NAME_2><NAME_1>NANANA52 OF 60MPQ8626 - P3V3_AUX
P12V_AUX
P3V3_RGMP3V3_AUXP3V3_LDO
P3V3_LDOP3V3_AUXP3V3_AUX
54EN_P3V3_RGM EN_P3V3_RGM_R1001%1/16W 0402LFCHIPCS11002FB075225V0.1UF
1%1/16WPWRGD_P3V3_AUX_RCS-2202FB01SW_P3V3_AUX_BST0.22UF1%SW_P3V3_AUX_BST_R0402LFTHE CAP & DAMPING RS FOR PWRGD SHOULD CLOSE TO DRIVE-END52P3V3_AUX_VCCCS36042FB041/16W1%SW_P3V3_AUX_FLTEN_P3V3_R15%CHIP00402LFSW_P3V3_AUX_SW04020402LF25VEN_P3V3_RGMALVC1G08009CH5104KEB0210%25VCH5104KEB02PWRGD_P3V3_RGM_RCS00002JB13EMPTYCS00002JB130402LFTP_U14_FLAG_NAL022811000CHIP2.2KAP22811AW5-7SMLFPWRGD_P1V8_AUX_R3CS00002JB13EMPTY5%00402LFTHE CAP & DAMPING RS FOR PWRGD SHOULD CLOSE TO DRIVE-END0402TMP_QCH2336K1B1212.4K1%CHIP1/16W1/16W2.2CHIP16VCH4223K1B00CV-3360MZ073.3UH/6AEN_P3V3PWRGD_P1V8_AUXC0805CH6223MEA01X6S20%16V22UF1/16WCS00002JB13P3V3_AUX_MODEPWRGD_EN_P3V3_R0402LF1/16WEN_P3V3CS00002JB1310%X6SCH5104KEB02CHIPCS25492FB0260.4KCHIP0402LFP3V3_AUX_REFCH4104K1B00X7R0402EMPTY10%0CHIP0402LF10%DELAY: 1.7MSX6S25V1UF5.49KC040210%1/16W1UF25V1/16W0402LFP3V3_AUX_CSCH4104K1B0010%
PWRGD_P1V8_AUX0402LFPWRGD_P1V8_AUX_R255PWRGD_P3V3_RGM555436PWRGD_P3V3_RGM_R3IC5436525551355254555652
543652555251 3553513552545556
CS11002FB0704020.001UF50V10%CH30106KB19EMPTYC0402CH6223MEA01EMPTY0 PWRGD_P5V_AUXCS00002JB13CH4104K1B000402X7RCH11006JB00C04020.1UFX7R0402CH4104K1B0074LVC1G08GW
BLM18SN220TN1D/8000MAX7R004020.1UF25V10%X7R
C0805X6S0402LFCS31002FB085%AL008626000X7RP3V3_AUX_FB_RCSMLFIND1%X6S20%10%CH4104K1B0016V
ICSM1/16W CHIP1%1001UF
CH6223MEA0116V0402LFPWRGD_P3V3_AUXCH4104K1B00ICSMLFAL001G32031MC74VHC1G32DTT1G25V0.1UF10%PWRGD_P5V_AUXCHIP10K
C040250V100PF0402LF5%0402C080525V040256KCHIP020%20% 20% 20% 20%10V 10V 10V0.1UF10%X7R50VIC25VX6SCH6222MEA0022UFC080522UFC0805X6S22UFX6SCH6222MEA0022UFC0805NPO1%X7R22UFIND0.1UFSMLFCX220TN1001MPQ8626GD-ZSMLF25V0.1UF22UFCH6222MEA00C08055%CHIPX7R10%3300PF CS31242FB020402CS35602FB0010%10VX6SCH6222MEA00
R529
R380
R709
R872 C305
4
1
2
5
4
1
2
3
C265
R99
21
PL35
PC239
PR532
PR276
PC273
3
13
8
11
2
9
14
1
12
6
5
4
10
7
PU1PC218PC219
15
2
34
U14
C252
C251
C240
PC229PC228PC227PC226
PL19
PR534
PC225
PR530
PC224
PR242
PC223
PC221
53
U18
U42
1 2SW1
CS
MODE
TRK_REF
SW2
PGND1
VCC
AGND
FB
BST
EN
PGND2
PGOODVIN
IN
FLG#EN
GND
OUT
1 2
Y
B
A
VCC
GND
IN_A
IN_B
OUT_Y
VCCGND
21
21R415
21
2121R869
21
21
2
1
2
1C296
2
1
2
1
2
1
21
21
2
1C151
CAD NOTE:
CAD NOTE:
21
2
1
2
1
2
1
2
1
2
1
2
1
2
1
2
1
2
1
2
1
21
2
1
2
1
2
1
2
1
2
1
SHEETDATE
DEPARTMENT
SIZE
PROJECT DOCUMENT NUMBER REV
REVIEWER
DESIGNER
123
7 3 2 1 6 5 4
E
A
B
C
E
D
C
B
A
7 6 5 4
D
IN
OUT
OUT
OUTIN
IN
OUT
OUT
IN
IN
IN
IN
IN
R871
C297
C262
R381
R293
C



2ND AL0096610021ST AL009059000IC TABLE
P2V5_AUXDC<+/-3%AC<+/-2%DESIGN SPECIFICATIONOUTPUT VOLTAGE=2.5VOUTPUT RIPPLE<+/-1%PD=(3.3-2.5)V*0.15A=0.12W
VNOM=0.8(1+RA/RB)=2.5Fri Aug 25 17:25:49 2023<NAME_2><NAME_1>NANANA53 OF 60RT9059 - P2V5_AUXP3V3_AUXP5V_AUXP3V3_AUXP2V5_AUXAL009059000CS00002JB130402LFTHE CAP & DAMPING RS FOR PWRGD SHOULD CLOSE TO DRIVE-ENDX7R10%CH6104KEA00C080525V10%CH6104KEA00PWRGD_P3V3_AUX_R210KCHIPEMPTY1/16W0PWRGD_P2V5_AUX_R0.001UF50V10%1/16WCS31002FB080402LFCS00002JB13PWRGD_P2V5_AUX_R3PWRGD_P3V3_AUXICRT9059GQWSMLFCS32552FB06U39_ADJ1%EMPTY0CHIP5235PWRGD_P2V5_AUX35541UF5%C0402CH5104KEB020CS00002JB1310%25VCH4104K1B000402LFCHIPC0402CH30106KB19CHIP1/16W10UF25V10%X6S0.1UF040210UFX6SC08050402LFX6S25V0402LF1%0402LF25.5KCS31202FB04CHIP1/16W1%12K
R873
R829
R830
3
2
1
9
8
710
5 TH
6
4
U39
R35
VIN3
VIN2
VOUT3
VOUT2
EP
VDD VIN1
VOUT1
ADJ
EN
PGOOD
21
2
1
2
1
2
1
2
1
2
1
21
2
1
CAD NOTE:
21
SHEETDATE
DEPARTMENT
SIZE
PROJECT DOCUMENT NUMBER REV
REVIEWER
DESIGNER
123
7 3 2 1 6 5 4
E
A
B
C
E
D
C
B
A
7 6 5 4
D
OUT
IN
OUT
C288
C291C289
R403
C287
R382
C153
C



DC<+/-3%DESIGN SPECIFICATIONOUTPUT RIPPLE<+/-1%AC<+/-2%OUTPUT VOLTAGE=1.8VPD=(3.3-1.8)V*0.33A=0.495WP1V8_AUX
PWRGD_FALL DELAY 230US2ND AL0096610021ST AL009059000IC TABLEVNOM=0.8(1+RA/RB)=1.8
Fri Aug 25 17:25:49 2023<NAME_2><NAME_1>NANANA54 OF 60RT9059 - P1V8_AUX
P3V3_AUXP3V3_LDOP1V8_AUXP3V3_AUXP5V_AUXCS31202FB04CHIP1/16WAL009059000EN_P1V8_R0402LF1/16WPWRGD_P2V5_AUX_R3CS00002JB13EMPTY5%5%CS00002JB130402LFCS00002JB130402LFPWRGD_P1V8_AUX_R1%1/16WCHIPCS31502FB050402LF10%X6SPWRGD_P3V3_RGM56THE CAP & DAMPING RS FOR PWRGD SHOULD CLOSE TO DRIVE-ENDCHIP001/16WCS00002JB130402LF1/16WCHIPCS31002FB08525354EN_P1V8PWRGD_P1V8_AUX_R3PWRGD_P1V8_AUX52 3655 5452365551355255CHIP00EMPTY12K1%EN_P1V8CH4104K1B000402X7R10%0.1UF25VAL001G32031MC74VHC1G32DTT1GSMLFCH30106KB19C040210KC0805CH6104KEA00 CH4104K1B000.001UF50V10%C0402CH5104KEB02RT9059GQWEMPTYC0402CH5104KEB02PWRGD_P3V3_RGM_R2U41_ADJX6S10%PWRGD_P5V_AUX0402LF1/16W CHIP
C0805CH6104KEA001%0402LF25V1UF10UF25VX6S10%25VX7R0.1UF040210%10UFSMLFIC15KX6S25V10%IC10025V1UF1%CS11002FB070402LF
R874
C310
5
4
1
2
3
R275
R831
R832
3
2
1
9
8
710
5 TH
6
4
U41
U49
VIN3
VIN2
VOUT3
VOUT2
EP
VDD VIN1
VOUT1
ADJ
EN
PGOOD
VCC
GND
IN_A
IN_B
OUT_Y
21
21
21R530
2
1
2
1C298
2
1
2
1 2
1
2
1
2
1
21
2
1
CAD NOTE:
21
SHEETDATE
DEPARTMENT
SIZE
PROJECT DOCUMENT NUMBER REV
REVIEWER
DESIGNER
123
7 3 2 1 6 5 4
E
A
B
C
E
D
C
B
A
7 6 5 4
D
OUT
OUT
IN
OUT
IN
IN
IN
R875
R406
C292
C293
C294C142
R393
C154
C



2ND TI USE 5V
OVER CURRENT PROTECTION(IC RATING)=4ACURRENT STEP=0.7ASLEW RATE=0.25A/USWORK FREQUENCY=750KHZ
1ST MPS USE 3V3R TABLEIC TABLE1ST AL0006950012ND AL051372000
TDC=0.73AMAX CURRENT=0.87ATRANSIENT TOLERANCE=+/-5%OUTPUT RIPPLE=+/-1%OUTPUT VOLTAGE=1.2VDESIGN SPECIFICATIONP1V2_AUX
Fri Aug 25 17:25:49 2023<NAME_2><NAME_1>NANANA55 OF 60NB695 - P1V2_AUX
P3V3_LDOP12V_AUXPVCC1_AUXPVCC1_AUXP5V_AUXPVCC1_AUXP3V3_AUXP1V2_AUXP3V3_AUX54 36PWRGD_P3V3_RGMTHE CAP & DAMPING RS FOR PWRGD SHOULD CLOSE TO DRIVE-ENDCHIPPWRGD_P1V2_AUX_R2EMPTY0CS00002JB13CS00002JB13EMPTY10%50V20%X6S0805PWRGD_P3V3_RGM_R3PWRGD_P1V8_AUXEN_P1V2_AUXBLM18SN220TN1D/8000MACX220TN1001SW_P1V2_AUX_FLTSMLFIND25VALVC1G08009CH4104K1B00PWRGD_P5V_AUXEN_P1V2_AUX55CH4104K1B00040255513552545652 36 565652543652CS00002JB130EMPTYEMPTYDCR=9MOHM0.001UFCH30106KB19C0402CH4223K1B0010%16V0.22UFPWRGD_P1V2_AUX_RCS31002FB08CHIPNB695GD-Z10UF0.1UF25V10%X7R040274LVC1G08GWSMX6SC0805X6SIC0.1UFCH6104KEA0025V0.1UFX7RCS-5102JB020402LFCHIP1/16W5%5.1CS41502FB040402LFCHIP1/16W1%150K0402LF10K1/16W1%
0402LF1/16W EMPTY5%0CS00002JB130402LF1/16W0 04020402P1V2_AUX_VCCX6SCH5104KEB021UF10%C040225VP1V2_AUX_MODE25V10%10%10UF4V20%22UFX6S0805TMP_QCH622KMEA014V080520%22UFX6S4V20%22UFX6S4V080522UF25V10%0.1UFCH4104K1B00X7R25V10%CH4104K1B00X7RSMLFAL000695001ICSMLF1UHCV-10B0MZ13INDCH6104KEA00X7RSW_P1V2_AUX_BSTSW_P1V2_AUX_SW10%C0805CS00002JB13CHIP5%00CHIPEN_P1V2_AUX_R040200402LFPWRGD_P1V2_AUX0402LF
R877
R876
4
1
2
R276
PR275
PR274
PC251PC252
R764
R708
PL29
PC259PC258PC257PC256PC255
PL31
PC254
PR498
PC253
12
1
8
2
13
7
6
5
3
4
9
11
10
PU41
PR539
PC250
PR496
53
U52
Y
B
A
1 2
1 2
3V3
SW
VOUT
MODE
C0
C1
LP#
AGND
BST
EN
PGND
PGVIN
VCCGND
21
21
2
1
2
1
2
1C155
CAD NOTE:
21
21
21
21
2
1
2
1
2
1
2
1
2
1
212
1
2
1
2
1
2
1
2
1
SHEETDATE
DEPARTMENT
SIZE
PROJECT DOCUMENT NUMBER REV
REVIEWER
DESIGNER
123
7 3 2 1 6 5 4
E
A
B
C
E
D
C
B
A
7 6 5 4
D
OUT
IN
OUTIN
IN
IN
IN
OUT
C301
C278
C



R TABLE1ST MPS USE 3V32ND TI USE 5V2ND AL0513720001ST AL000695001
SLEW RATE=0.25A/USCURRENT STEP=0.89AOVER CURRENT PROTECTION(IC RATING)=4ADESIGN SPECIFICATIONOUTPUT VOLTAGE=1.0VOUTPUT RIPPLE=+/-1%TRANSIENT TOLERANCE=+/-5%MAX CURRENT=0.89ATDC=0.74AWORK FREQUENCY=750KHZ
IC TABLEP1V0_AUX
Fri Aug 25 17:25:49 2023<NAME_2><NAME_1>NANANA56 OF 60NB695 - P1V0_AUXP5V_AUXP3V3_AUXPVCC2_AUX
P3V3_LDO
PVCC2_AUXP1V0_AUXP3V3_AUXPVCC2_AUXP12V_AUXICTHE CAP & DAMPING RS FOR PWRGD SHOULD CLOSE TO DRIVE-ENDPWRGD_P1V0_AUX1UHDCR=9MOHMPWRGD_P1V2_AUX_R2SW_P1V0_AUX_FLTBLM18SN220TN1D/8000MAINDSMLFCX220TN1001PWRGD_P1V2_AUXPWRGD_P5V_AUX355136 5555 54 52ALVC1G08009EN_P1V0_AUX561%CH30106KB19C0402CH4223K1B000402LF1/16W56X6S X6SCH4104K1B00EN_P1V0_AUX_RCS00002JB130EN_P1V0_AUX555%SW_P1V0_AUX_BSTPWRGD_P1V0_AUX_RCS00002JB1322 3625V
P1V0_AUX_VCCCH5104KEB02C0402CS00002JB13CH6104KEA00C080510UF10%74LVC1G08GWCH4104K1B00CH6104KEA00C08050.1UF25VCV-10B0MZ13X7R0402X7R22UF4V20%AL00069500125V10%1UFX6S25V4V080520%22UFTMP_QCH622KMEA01X6S4V080520%22UFX6S4V080520%22UFX6S0805X6S25V10%0.1UFCH4104K1B00X7R10%0.22UF25VICSMLF0.1UF10%040204021/16WCHIP10K0CHIP0402LF05%1/16W CHIP 0402LFCS00002JB1305%EMPTY1/16W 0402LFCS00002JB135.15%1/16WCHIP0402LFX7RCH4104K1B000.1UF10%0402SW_P1V0_AUX_SWSM0402CS-5102JB0210UF25V10%10%P1V0_AUX_MODECS41002FB09CHIP0402LF1/16W1%100KCS31002FB080402LF0CHIP1/16W0402LFEMPTYX7R5%SMLFIND10%EMPTY50V16V0.001UFNB695GD-Z
PR543
4
1
2
R277
PR205
PR193
PC261PC262
PL33
PL32
PC270PC269PC268PC267PC266
PC264
PR500
PC263
12
1
8
2
13
7
6
5
3
4
9
11
10
PU42
PR541
PC260
53
U53
Y
B
A
1 2
1 2
3V3
SW
VOUT
MODE
C0
C1
LP#
AGND
BST
EN
PGND
PGVIN
VCCGND
21
2
1
2
1
2
1
21
2
1C156
CAD NOTE:
21
21
21
2
1
2
1
2
1
2
1
2
1
2
1
2
1
2
1
2
1
SHEETDATE
DEPARTMENT
SIZE
PROJECT DOCUMENT NUMBER REV
REVIEWER
DESIGNER
123
7 3 2 1 6 5 4
E
A
B
C
E
D
C
B
A
7 6 5 4
D
IN
OUTIN
IN
IN
OUT
R878
C302
C280
R399
C



Fri Aug 25 17:25:50 2023<NAME_2><NAME_1>NANANA57 OF 60HOLESI39I41I43THTMP-C_HOLE8EMPTYTHHOLE620HOLE1211EMPTYTHEMPTYBSM NUTEMPTYHOLE1247THDUMMY50EMPTYHOLE1248THTHHOLE1211EMPTYBOT NUTTHTMP-C_HOLE8EMPTYTOOLING HOLEDUMMY50EMPTYTHTOP NUTTPM NUTTHEMPTYEMPTYTHHOLE620
1
1
1
1
1
1
1
H9
1
H5
1
H2B2
1
H2B1
H7
H6
H1
H2
H4
H3
1
1
1
1
1
1
1
1
1
1
BOM NOTE:BOM NOTE:
BOM NOTE: BOM NOTE: BOM NOTE:
SHEETDATE
DEPARTMENT
SIZE
PROJECT DOCUMENT NUMBER REV
REVIEWER
DESIGNER
123
7 3 2 1 6 5 4
E
A
B
C
E
D
C
B
A
7 6 5 4
D
C



5 INCH DELTA L10 INCH DELTA L
Fri Aug 25 17:25:50 2023<NAME_2><NAME_1>NANANA58 OF 60DELTA - LGND_P1
GND_P1
GND_P1GND_P1GND_P1GND_P1GND_P1GND_P1GND_P1
GND_P1 GND_P1GND_P1GND_P1
GND_P1
GND_P1GND_P1SMLFDELTA-L 4.085_5INCH_IN1_DPEMPTY85_5INCH_IN4_DP85_5INCH_IN4_DNSMLFDELTA-L 4.0TP3385_5INCH_BOT_DP85_5INCH_BOT_DNSMLFDELTA-L 4.0TP33EMPTY85_10INCH_IN4_DP85_10INCH_IN4_DNSMLFDELTA-L 4.0TP33EMPTYEMPTYTP33DELTA-L 4.085_10INCH_BOT_DP85_10INCH_BOT_DNSMLFSMLFDELTA-L 4.0DELTA-L 4.0EMPTYTP3385_10INCH_IN1_DPEMPTYTP33DELTA-L 4.0SMLFTP33EMPTY85_10INCH_IN1_DN85_10INCH_TOP_DP85_10INCH_TOP_DNSMLFSMLFDELTA-L 4.0DELTA-L 4.0TP33EMPTYTP33EMPTYEMPTYDELTA-L 4.0SMLF85_5INCH_IN1_DN85_5INCH_TOP_DP85_5INCH_TOP_DNDELTA-L 4.0SMLFTP33EMPTY
SMLFTP33DELTA-L 4.0SMLFEMPTYTP33SMLFDELTA-L 4.0EMPTYTP33EMPTYTP33EMPTYTP33SMLFSMLFDELTA-L 4.0EMPTYTP33DELTA-L 4.0
32
1
32
1
32
1
32
132
1
32
1
32
1
32
1
3 2
1
3 2
1
3 2
1
3 2
1
3 2
1
3 2
1
3 2
1
3 2
1
J27
J26
J28
J25
J17
J16
J11
J9
1_P
3_G2_N
1_P
3_G2_N
1_P
3_G2_N
1_P
3_G2_N
1_P
3_G2_N
1_P
3_G2_N
1_P
3_G2_N
1_P
3_G2_N
1_P
3_G 2_N
1_P
3_G 2_N
1_P
3_G 2_N
1_P
3_G 2_N
1_P
3_G 2_N
1_P
3_G 2_N
1_P
3_G 2_N
1_P
3_G 2_N
J19J20J23J24J30J22J29J12
SHEETDATE
DEPARTMENT
SIZE
PROJECT DOCUMENT NUMBER REV
REVIEWER
DESIGNER
123
7 3 2 1 6 5 4
E
A
B
C
E
D
C
B
A
7 6 5 4
D
C



SN LABELMAC LABELSN+VPN+FB PN LABELHCF0A001010EFI BIOS LABEL BMC AMI LABELHCF0E016010HCLU2002010HCF0E015010HCS2F014010
Fri Aug 25 17:25:50 2023<NAME_2><NAME_1>NANANA59 OF 60DUMMY SYMBOL
SNLABEL_7X7EMPTYBIOS_FLASHDUMMY9DUMMY69MECHMECHQUANTA_LOGO_7X26BMC_FLASHMECHEMPTYDUMMY2EMPTYMECHDUMMY1WEEEEMPTYDUMMY8EMPTYEMPTYMECHMECHBMC_FLASHDUMMY8DUMMY3MECHPB-E1_SMALLMECH
11
1
111
DM2DM1
DM3
ME4
DM7
ME2ME1
DUMMY_SYMBOLDUMMY_SYMBOL
DUMMY_SYMBOL
ME_PART Symbol
ME_PART Symbol
ME_PART SymbolME_PART Symbol
SHEETDATE
REVIEWER
DESIGNERDEPARTMENT
SIZE
PROJECT DOCUMENT NUMBER REV
123
7 3 2 1 6 5 4
E
A
B
C
E
D
C
B
A
7 6 5 4
D
C
QUANTA_LOGO PB-E1 BIOS-BMCLABEL BARCODE PCB_VENDOR_LOGO
BMC_FLASH BIOS_FLASH MECHANIC_SYMBOL
PCBA_LABEL
HEATSINK BATTERY_SYMBOL
QCT_LOGO
PICKUP_SYMBOLPICKUP_SYMBOL
CBS_SYMBOL TOOLING-HOLESYMBOL
WEEE



Fri Aug 25 17:25:50 2023<NAME_2><NAME_1>NANANA60 OF 60TDR
T_GNDT_GNDT_GNDT_GNDT_GNDT_GNDGND_P1GND_P1 GND_P1GND_P1 GND_P1GND_P1GND_P1GND_P1GND_P1GND_P1GND_P1 GND_P1GND_P1GND_P1GND_P1 GND_P1TDR_SE_50_OHM_IN1TDR_SE_50_OHM_IN2TDR_SE_50_OHM_IN3TDR_SE_50_OHM_IN4TDR_DIFF_100_TOP_DNTDR_DIFF_100_TOP_DPTDR_DIFF_100_IN1_DPTDR_DIFF_100_IN1_DNTDR_DIFF_100_IN4_DPTDR_DIFF_100_IN4_DNTDR_DIFF_100_BOT_DPTDR_DIFF_100_BOT_DN
TDR_DIFF_85_TOP_DPTDR_DIFF_85_TOP_DNTDR_DIFF_85_IN1_DPTDR_DIFF_85_IN4_DPTDR_DIFF_85_IN4_DNTDR_DIFF_85_BOT_DPTDR_DIFF_85_BOT_DN
TP15TP_TDR_4P_DIPEMPTYTHEMPTYTP15TP_TDR_4P_DIPTHTP15TP_TDR_4P_DIPEMPTYTHTP15TP_TDR_4P_DIPEMPTYTHTP15TP_TDR_4P_DIPEMPTYTHTP15TP_TDR_4P_DIPEMPTYTH
TP_TDR_4P_DIPTHEMPTYTP15THEMPTYTP_TDR_4P_DIPTP15THEMPTYTP_TDR_4P_DIPTP15THEMPTYTP_TDR_4P_DIPTP15THEMPTYTHEMPTYTP_TDR_4P_DIPTP15THEMPTYTP_TDR_4P_DIPTP15THEMPTYTP_TDR_4P_DIPTP15
TP_TDR_4P_DIPTP15EMPTYTHTP15TP_TDR_4P_DIPEMPTYTHTH2TH2TH2TH2TH2TDR_SE_50_OHM_TOPTDR_SE_50_OHM_BOTTH2TP_TDR_4P_DIPTP15TDR_DIFF_85_IN1_DN
4
1
3
24
1
3
2
4
1
3
24
1
3
2
4
1
3
24
1
3
2
4
1
3
2 4
1
3
2
4
1
3
2 4
1
3
2
4
1
3
2 4
1
3
2
4
1
3
2 4
1
3
2
4
1
3
24
1
3
2
3
2
1
3
2
1
3
2
1
3
2
1
3
2
1
3
2
1
TDR
TDR
TDR
TDR
TDR
TDR
X20X14
X23X17
X24X18
X13 X19
X2 X8
X5 X11
X6 X12
X7X1
S1
P2S2
P1
S1
P2 S2
P1
S1
P2S2
P1
S1
P2 S2
P1
S1
P2S2
P1
S1
P2 S2
P1
S1
P2 S2
P1
S1
P2S2
P1
S1
P2 S2
P1
S1
P2S2
P1
S1
P2 S2
P1
S1
P2S2
P1
S1
P2 S2
P1
S1
P2S2
P1
S1
P2S2
P1
S1
P2 S2
P1
SHEETDATE
DEPARTMENT
SIZE
PROJECT DOCUMENT NUMBER REV
REVIEWER
DESIGNER
DB2
DB3
DB4
DB5
DB6
DB1
123
7 3 2 1 6 5 4
E
A
B
C
E
D
C
B
A
7 6 5 4
D
C